FILE_TYPE = MACRO_DRAWING;
SET COLOR_WIRE YELLOW;
SET COLOR_PROP ORANGE;
SET COLOR_DOT WHITE;
SET COLOR_ARC YELLOW;
SET COLOR_BODY GREEN;
SET COLOR_NOTE PURPLE;
SET PROP_DISPLAY VALUE;
SET PAGE_NUMBER P161;
FORCEADD OFFPAGE_BI..1
R 4
(-11400 8150);
FORCEPROP 2 LAST $XR0 24J12< 
J 0
(-11619 8150);
DISPLAY 0.638298 (-11619 8150);
PAINT MONO (-11619 8150);
FORCEPROP 2 LAST CDS_LIB cls
J 0
(-11400 8150);
DISPLAY INVISIBLE (-11400 8150);
FORCEPROP 1 LAST CDS_LMAN_SYM_OUTLINE -50,50,50,-50
R 2
J 0
(-11400 8150);
DISPLAY 0.468085 (-11400 8150);
PAINT GREEN (-11400 8150);
DISPLAY INVISIBLE (-11400 8150);
FORCEPROP 1 LAST BODY_TYPE COMMENT
R 2
J 0
(-11410 8015);
DISPLAY 0.808511 (-11410 8015);
PAINT GREEN (-11410 8015);
DISPLAY INVISIBLE (-11410 8015);
FORCEPROP 1 LAST OFFPAGE TRUE
R 2
J 0
(-11410 8095);
DISPLAY 0.808511 (-11410 8095);
PAINT GREEN (-11410 8095);
DISPLAY INVISIBLE (-11410 8095);
FORCEPROP 2 LAST PATH I100
J 0
(-11350 8250);
DISPLAY 1.021277 (-11350 8250);
DISPLAY INVISIBLE (-11350 8250);
FORCEADD OFFPAGE_BI..1
R 4
(-11400 8050);
FORCEPROP 2 LAST $XR0 24J12<> 
J 0
(-11650 8050);
DISPLAY 0.638298 (-11650 8050);
PAINT MONO (-11650 8050);
FORCEPROP 2 LAST CDS_LIB cls
J 0
(-11400 8050);
DISPLAY INVISIBLE (-11400 8050);
FORCEPROP 1 LAST CDS_LMAN_SYM_OUTLINE -50,50,50,-50
R 2
J 0
(-11400 8050);
DISPLAY 0.468085 (-11400 8050);
PAINT GREEN (-11400 8050);
DISPLAY INVISIBLE (-11400 8050);
FORCEPROP 1 LAST BODY_TYPE COMMENT
R 2
J 0
(-11410 7915);
DISPLAY 0.808511 (-11410 7915);
PAINT GREEN (-11410 7915);
DISPLAY INVISIBLE (-11410 7915);
FORCEPROP 1 LAST OFFPAGE TRUE
R 2
J 0
(-11410 7995);
DISPLAY 0.808511 (-11410 7995);
PAINT GREEN (-11410 7995);
DISPLAY INVISIBLE (-11410 7995);
FORCEPROP 2 LAST PATH I104
J 0
(-11350 8150);
DISPLAY 1.021277 (-11350 8150);
DISPLAY INVISIBLE (-11350 8150);
FORCEADD GND_SG..1
(-13150 6100);
FORCEPROP 3 LASTPIN (-13100 6150) SIG_NAME SG\g
J 0
(-13090 6160);
DISPLAY 0.659574 (-13090 6160);
PAINT MONO (-13090 6160);
DISPLAY INVISIBLE (-13090 6160);
FORCEPROP 1 LAST HDL_POWER SG
J 1
(-13095 6005);
DISPLAY 0.808511 (-13095 6005);
PAINT GREEN (-13095 6005);
FORCEPROP 1 LAST PATH I136
J 0
(-13115 6100);
DISPLAY 0.808511 (-13115 6100);
PAINT GREEN (-13115 6100);
DISPLAY INVISIBLE (-13115 6100);
FORCEPROP 1 LAST BODY_TYPE PLUMBING
J 0
(-13135 6085);
DISPLAY 0.808511 (-13135 6085);
PAINT GREEN (-13135 6085);
DISPLAY INVISIBLE (-13135 6085);
FORCEPROP 2 LAST CDS_LIB cls
J 0
(-13150 6100);
DISPLAY INVISIBLE (-13150 6100);
FORCEPROP 1 LAST CDS_LMAN_SYM_OUTLINE 0,0,100,-50
J 0
(-13150 6100);
DISPLAY 0.468085 (-13150 6100);
PAINT GREEN (-13150 6100);
DISPLAY INVISIBLE (-13150 6100);
FORCEADD OFFPAGE_OUT..1
R 2
(-11400 5050);
FORCEPROP 2 LAST $XR0 16C4< 
J 0
(-11583 5050);
DISPLAY 0.638298 (-11583 5050);
PAINT MONO (-11583 5050);
FORCEPROP 1 LAST BODY_TYPE COMMENT
J 2
(-11410 5185);
DISPLAY 0.808511 (-11410 5185);
PAINT GREEN (-11410 5185);
DISPLAY INVISIBLE (-11410 5185);
FORCEPROP 1 LAST CDS_LMAN_SYM_OUTLINE -50,50,50,-50
J 2
(-11400 5050);
DISPLAY 0.468085 (-11400 5050);
PAINT GREEN (-11400 5050);
DISPLAY INVISIBLE (-11400 5050);
FORCEPROP 2 LAST CDS_LIB cls
J 0
(-11400 5050);
DISPLAY INVISIBLE (-11400 5050);
FORCEPROP 1 LAST OFFPAGE TRUE
J 2
(-11410 5105);
DISPLAY 0.808511 (-11410 5105);
PAINT GREEN (-11410 5105);
DISPLAY INVISIBLE (-11410 5105);
FORCEPROP 2 LAST PATH I139
J 0
(-11350 5150);
DISPLAY 1.021277 (-11350 5150);
DISPLAY INVISIBLE (-11350 5150);
FORCEADD RESISTOR..2
R 1
(-12600 7300);
FORCEPROP 1 LAST $LOCATION R270
J 0
(-12950 7300);
DISPLAY 1.212766 (-12950 7300);
PAINT GREEN (-12950 7300);
FORCEPROP 0 LAST CDS_LOCATION R270
R 1
J 0
(-12350 7400);
DISPLAY 1.021277 (-12350 7400);
DISPLAY INVISIBLE (-12350 7400);
FORCEPROP 0 LAST $SEC 1
R 1
J 0
(-12350 7400);
DISPLAY 0.680851 (-12350 7400);
PAINT MONO (-12350 7400);
DISPLAY INVISIBLE (-12350 7400);
FORCEPROP 0 LAST CDS_SEC 1
R 1
J 0
(-12350 7400);
DISPLAY 1.021277 (-12350 7400);
DISPLAY INVISIBLE (-12350 7400);
FORCEPROP 0 LASTPIN (-12700 7300) $PN 1
J 2
(-12710 7310);
DISPLAY 0.680851 (-12710 7310);
PAINT MONO (-12710 7310);
FORCEPROP 0 LASTPIN (-12450 7300) $PN 2
J 0
(-12440 7310);
DISPLAY 0.680851 (-12440 7310);
PAINT MONO (-12440 7310);
FORCEPROP 0 LAST PACKAGE 0402
J 0
(-12650 7350);
DISPLAY 1.021277 (-12650 7350);
FORCEPROP 1 LAST VALUE 4.7KOHM
J 0
(-12350 7300);
DISPLAY 1.212766 (-12350 7300);
PAINT GREEN (-12350 7300);
FORCEPROP 1 LAST PATH I140
R 1
J 0
(-12705 7103);
DISPLAY 1.212766 (-12705 7103);
PAINT GREEN (-12705 7103);
DISPLAY INVISIBLE (-12705 7103);
FORCEPROP 1 LAST TOLERANCE 1%
R 1
J 0
(-12855 7103);
DISPLAY 1.212766 (-12855 7103);
PAINT GREEN (-12855 7103);
DISPLAY INVISIBLE (-12855 7103);
FORCEPROP 2 LAST CDS_LIB passive
J 0
(-12600 7300);
DISPLAY INVISIBLE (-12600 7300);
FORCEPROP 1 LAST CDS_LMAN_SYM_OUTLINE -50,50,50,-100
R 1
J 0
(-12600 7300);
DISPLAY 0.468085 (-12600 7300);
PAINT GREEN (-12600 7300);
DISPLAY INVISIBLE (-12600 7300);
FORCEPROP 1 LAST CLS_PN G155-14701-01
R 1
J 0
(-12800 7164);
DISPLAY 1.212766 (-12800 7164);
PAINT GREEN (-12800 7164);
DISPLAY INVISIBLE (-12800 7164);
FORCEADD OFFPAGE_OUT..1
R 2
(-11400 7950);
FORCEPROP 2 LAST $XR0 16H3< 
J 0
(-11583 7950);
DISPLAY 0.638298 (-11583 7950);
PAINT MONO (-11583 7950);
FORCEPROP 1 LAST CDS_LMAN_SYM_OUTLINE -50,50,50,-50
J 2
(-11400 7950);
DISPLAY 0.468085 (-11400 7950);
PAINT GREEN (-11400 7950);
DISPLAY INVISIBLE (-11400 7950);
FORCEPROP 2 LAST CDS_LIB cls
J 0
(-11400 7950);
DISPLAY INVISIBLE (-11400 7950);
FORCEPROP 2 LAST PATH I143
J 0
(-11350 8050);
DISPLAY 1.021277 (-11350 8050);
DISPLAY INVISIBLE (-11350 8050);
FORCEPROP 1 LAST OFFPAGE TRUE
J 2
(-11410 8005);
DISPLAY 0.808511 (-11410 8005);
PAINT GREEN (-11410 8005);
DISPLAY INVISIBLE (-11410 8005);
FORCEPROP 1 LAST BODY_TYPE COMMENT
J 2
(-11410 8085);
DISPLAY 0.808511 (-11410 8085);
PAINT GREEN (-11410 8085);
DISPLAY INVISIBLE (-11410 8085);
FORCEADD OFFPAGE_IN..2
R 2
(-11400 6850);
FORCEPROP 2 LAST $XR0 21D13> 
J 0
(-11614 6850);
DISPLAY 0.638298 (-11614 6850);
PAINT MONO (-11614 6850);
FORCEPROP 1 LAST BODY_TYPE COMMENT
J 2
(-11410 6985);
DISPLAY 0.808511 (-11410 6985);
PAINT GREEN (-11410 6985);
DISPLAY INVISIBLE (-11410 6985);
FORCEPROP 1 LAST CDS_LMAN_SYM_OUTLINE -50,50,50,-50
J 2
(-11400 6850);
DISPLAY 0.468085 (-11400 6850);
PAINT GREEN (-11400 6850);
DISPLAY INVISIBLE (-11400 6850);
FORCEPROP 2 LAST CDS_LIB cls
J 2
(-11400 6850);
DISPLAY INVISIBLE (-11400 6850);
FORCEPROP 1 LAST OFFPAGE TRUE
J 2
(-11410 6905);
DISPLAY 0.808511 (-11410 6905);
PAINT GREEN (-11410 6905);
DISPLAY INVISIBLE (-11410 6905);
FORCEPROP 2 LAST PATH I16
J 0
(-11350 6950);
DISPLAY 1.021277 (-11350 6950);
DISPLAY INVISIBLE (-11350 6950);
FORCEADD OFFPAGE_IN..2
R 2
(-11400 6950);
FORCEPROP 2 LAST $XR0 21G7> 
J 0
(-11583 6950);
DISPLAY 0.638298 (-11583 6950);
PAINT MONO (-11583 6950);
FORCEPROP 1 LAST CDS_LMAN_SYM_OUTLINE -50,50,50,-50
J 2
(-11400 6950);
DISPLAY 0.468085 (-11400 6950);
PAINT GREEN (-11400 6950);
DISPLAY INVISIBLE (-11400 6950);
FORCEPROP 2 LAST CDS_LIB cls
J 0
(-11400 6950);
DISPLAY INVISIBLE (-11400 6950);
FORCEPROP 1 LAST BODY_TYPE COMMENT
J 2
(-11410 7085);
DISPLAY 0.808511 (-11410 7085);
PAINT GREEN (-11410 7085);
DISPLAY INVISIBLE (-11410 7085);
FORCEPROP 1 LAST OFFPAGE TRUE
J 2
(-11410 7005);
DISPLAY 0.808511 (-11410 7005);
PAINT GREEN (-11410 7005);
DISPLAY INVISIBLE (-11410 7005);
FORCEPROP 2 LAST PATH I17
J 0
(-11350 7050);
DISPLAY 1.021277 (-11350 7050);
DISPLAY INVISIBLE (-11350 7050);
FORCEADD OFFPAGE_BI..1
(-4650 4150);
FORCEPROP 2 LAST $XR0 24J12< 
J 0
(-4590 4150);
DISPLAY 0.638298 (-4590 4150);
PAINT MONO (-4590 4150);
FORCEPROP 2 LAST PATH I19
J 0
(-4600 4250);
DISPLAY 1.021277 (-4600 4250);
DISPLAY INVISIBLE (-4600 4250);
FORCEPROP 1 LAST OFFPAGE TRUE
J 0
(-4640 4205);
DISPLAY 0.808511 (-4640 4205);
PAINT GREEN (-4640 4205);
DISPLAY INVISIBLE (-4640 4205);
FORCEPROP 1 LAST BODY_TYPE COMMENT
J 0
(-4640 4285);
DISPLAY 0.808511 (-4640 4285);
PAINT GREEN (-4640 4285);
DISPLAY INVISIBLE (-4640 4285);
FORCEPROP 1 LAST CDS_LMAN_SYM_OUTLINE -50,50,50,-50
J 0
(-4650 4150);
DISPLAY 0.468085 (-4650 4150);
PAINT GREEN (-4650 4150);
DISPLAY INVISIBLE (-4650 4150);
FORCEPROP 2 LAST CDS_LIB cls
J 0
(-4650 4150);
DISPLAY INVISIBLE (-4650 4150);
FORCEADD XC7A200T_2FBG484C_FBG484..2
(-9500 8650);
FORCEPROP 1 LAST $LOCATION U24
J 0
(-9450 8750);
DISPLAY 1.212766 (-9450 8750);
PAINT GREEN (-9450 8750);
FORCEPROP 0 LAST CDS_LOCATION U24
J 0
(-9450 9050);
DISPLAY 1.021277 (-9450 9050);
DISPLAY INVISIBLE (-9450 9050);
FORCEPROP 0 LAST $SEC 2
J 0
(-9450 9050);
DISPLAY 0.680851 (-9450 9050);
PAINT MONO (-9450 9050);
DISPLAY INVISIBLE (-9450 9050);
FORCEPROP 0 LAST CDS_SEC 2
J 0
(-9450 9050);
DISPLAY 1.021277 (-9450 9050);
DISPLAY INVISIBLE (-9450 9050);
FORCEPROP 0 LASTPIN (-9600 8550) $PN Y17
J 2
(-9610 8560);
DISPLAY 0.680851 (-9610 8560);
PAINT MONO (-9610 8560);
FORCEPROP 0 LASTPIN (-6600 8550) $PN P20
J 0
(-6590 8560);
DISPLAY 0.680851 (-6590 8560);
PAINT MONO (-6590 8560);
FORCEPROP 0 LASTPIN (-6600 8350) $PN N15
J 0
(-6590 8360);
DISPLAY 0.680851 (-6590 8360);
PAINT MONO (-6590 8360);
FORCEPROP 0 LASTPIN (-9600 8250) $PN AA16
J 2
(-9610 8260);
DISPLAY 0.680851 (-9610 8260);
PAINT MONO (-9610 8260);
FORCEPROP 0 LASTPIN (-6600 8050) $PN R22
J 0
(-6590 8060);
DISPLAY 0.680851 (-6590 8060);
PAINT MONO (-6590 8060);
FORCEPROP 0 LASTPIN (-9600 8350) $PN Y16
J 2
(-9610 8360);
DISPLAY 0.680851 (-9610 8360);
PAINT MONO (-9610 8360);
FORCEPROP 0 LASTPIN (-6600 8150) $PN P22
J 0
(-6590 8160);
DISPLAY 0.680851 (-6590 8160);
PAINT MONO (-6590 8160);
FORCEPROP 0 LASTPIN (-9600 8050) $PN AB17
J 2
(-9610 8060);
DISPLAY 0.680851 (-9610 8060);
PAINT MONO (-9610 8060);
FORCEPROP 0 LASTPIN (-6600 7850) $PN R21
J 0
(-6590 7860);
DISPLAY 0.680851 (-6590 7860);
PAINT MONO (-6590 7860);
FORCEPROP 0 LASTPIN (-9600 8150) $PN AB16
J 2
(-9610 8160);
DISPLAY 0.680851 (-9610 8160);
PAINT MONO (-9610 8160);
FORCEPROP 0 LASTPIN (-6600 7950) $PN P21
J 0
(-6590 7960);
DISPLAY 0.680851 (-6590 7960);
PAINT MONO (-6590 7960);
FORCEPROP 0 LASTPIN (-9600 7850) $PN AB13
J 2
(-9610 7860);
DISPLAY 0.680851 (-9610 7860);
PAINT MONO (-9610 7860);
FORCEPROP 0 LASTPIN (-6600 7650) $PN V22
J 0
(-6590 7660);
DISPLAY 0.680851 (-6590 7660);
PAINT MONO (-6590 7660);
FORCEPROP 0 LASTPIN (-9600 7950) $PN AA13
J 2
(-9610 7960);
DISPLAY 0.680851 (-9610 7960);
PAINT MONO (-9610 7960);
FORCEPROP 0 LASTPIN (-6600 7750) $PN U22
J 0
(-6590 7760);
DISPLAY 0.680851 (-6590 7760);
PAINT MONO (-6590 7760);
FORCEPROP 0 LASTPIN (-9600 7650) $PN AB15
J 2
(-9610 7660);
DISPLAY 0.680851 (-9610 7660);
PAINT MONO (-9610 7660);
FORCEPROP 0 LASTPIN (-6600 7450) $PN U21
J 0
(-6590 7460);
DISPLAY 0.680851 (-6590 7460);
PAINT MONO (-6590 7460);
FORCEPROP 0 LASTPIN (-9600 7750) $PN AA15
J 2
(-9610 7760);
DISPLAY 0.680851 (-9610 7760);
PAINT MONO (-9610 7760);
FORCEPROP 0 LASTPIN (-6600 7550) $PN T21
J 0
(-6590 7560);
DISPLAY 0.680851 (-6590 7560);
PAINT MONO (-6590 7560);
FORCEPROP 0 LASTPIN (-9600 7450) $PN AA14
J 2
(-9610 7460);
DISPLAY 0.680851 (-9610 7460);
PAINT MONO (-9610 7460);
FORCEPROP 0 LASTPIN (-6600 7250) $PN R19
J 0
(-6590 7260);
DISPLAY 0.680851 (-6590 7260);
PAINT MONO (-6590 7260);
FORCEPROP 0 LASTPIN (-9600 7550) $PN Y13
J 2
(-9610 7560);
DISPLAY 0.680851 (-9610 7560);
PAINT MONO (-9610 7560);
FORCEPROP 0 LASTPIN (-6600 7350) $PN P19
J 0
(-6590 7360);
DISPLAY 0.680851 (-6590 7360);
PAINT MONO (-6590 7360);
FORCEPROP 0 LASTPIN (-6600 7050) $PN T20
J 0
(-6590 7060);
DISPLAY 0.680851 (-6590 7060);
PAINT MONO (-6590 7060);
FORCEPROP 0 LASTPIN (-9600 7250) $PN Y14
J 2
(-9610 7260);
DISPLAY 0.680851 (-9610 7260);
PAINT MONO (-9610 7260);
FORCEPROP 0 LASTPIN (-9600 7350) $PN W14
J 2
(-9610 7360);
DISPLAY 0.680851 (-9610 7360);
PAINT MONO (-9610 7360);
FORCEPROP 0 LASTPIN (-6600 7150) $PN T19
J 0
(-6590 7160);
DISPLAY 0.680851 (-6590 7160);
PAINT MONO (-6590 7160);
FORCEPROP 0 LASTPIN (-9600 7050) $PN AB12
J 2
(-9610 7060);
DISPLAY 0.680851 (-9610 7060);
PAINT MONO (-9610 7060);
FORCEPROP 0 LASTPIN (-6600 6850) $PN W22
J 0
(-6590 6860);
DISPLAY 0.680851 (-6590 6860);
PAINT MONO (-6590 6860);
FORCEPROP 0 LASTPIN (-9600 7150) $PN AB11
J 2
(-9610 7160);
DISPLAY 0.680851 (-9610 7160);
PAINT MONO (-9610 7160);
FORCEPROP 0 LASTPIN (-6600 6950) $PN W21
J 0
(-6590 6960);
DISPLAY 0.680851 (-6590 6960);
PAINT MONO (-6590 6960);
FORCEPROP 0 LASTPIN (-9600 6850) $PN AB10
J 2
(-9610 6860);
DISPLAY 0.680851 (-9610 6860);
PAINT MONO (-9610 6860);
FORCEPROP 0 LASTPIN (-6600 6650) $PN AA21
J 0
(-6590 6660);
DISPLAY 0.680851 (-6590 6660);
PAINT MONO (-6590 6660);
FORCEPROP 0 LASTPIN (-9600 6950) $PN AA9
J 2
(-9610 6960);
DISPLAY 0.680851 (-9610 6960);
PAINT MONO (-9610 6960);
FORCEPROP 0 LASTPIN (-6600 6750) $PN AA20
J 0
(-6590 6760);
DISPLAY 0.680851 (-6590 6760);
PAINT MONO (-6590 6760);
FORCEPROP 0 LASTPIN (-9600 6650) $PN AA11
J 2
(-9610 6660);
DISPLAY 0.680851 (-9610 6660);
PAINT MONO (-9610 6660);
FORCEPROP 0 LASTPIN (-6600 6450) $PN Y22
J 0
(-6590 6460);
DISPLAY 0.680851 (-6590 6460);
PAINT MONO (-6590 6460);
FORCEPROP 0 LASTPIN (-9600 6750) $PN AA10
J 2
(-9610 6760);
DISPLAY 0.680851 (-9610 6760);
PAINT MONO (-9610 6760);
FORCEPROP 0 LASTPIN (-6600 6550) $PN Y21
J 0
(-6590 6560);
DISPLAY 0.680851 (-6590 6560);
PAINT MONO (-6590 6560);
FORCEPROP 0 LASTPIN (-9600 6450) $PN W10
J 2
(-9610 6460);
DISPLAY 0.680851 (-9610 6460);
PAINT MONO (-9610 6460);
FORCEPROP 0 LASTPIN (-6600 6250) $PN AB22
J 0
(-6590 6260);
DISPLAY 0.680851 (-6590 6260);
PAINT MONO (-6590 6260);
FORCEPROP 0 LASTPIN (-9600 6550) $PN V10
J 2
(-9610 6560);
DISPLAY 0.680851 (-9610 6560);
PAINT MONO (-9610 6560);
FORCEPROP 0 LASTPIN (-6600 6350) $PN AB21
J 0
(-6590 6360);
DISPLAY 0.680851 (-6590 6360);
PAINT MONO (-6590 6360);
FORCEPROP 0 LASTPIN (-9600 6250) $PN Y12
J 2
(-9610 6260);
DISPLAY 0.680851 (-9610 6260);
PAINT MONO (-9610 6260);
FORCEPROP 0 LASTPIN (-6600 6050) $PN V20
J 0
(-6590 6060);
DISPLAY 0.680851 (-6590 6060);
PAINT MONO (-6590 6060);
FORCEPROP 0 LASTPIN (-9600 6350) $PN Y11
J 2
(-9610 6360);
DISPLAY 0.680851 (-9610 6360);
PAINT MONO (-9610 6360);
FORCEPROP 0 LASTPIN (-6600 6150) $PN U20
J 0
(-6590 6160);
DISPLAY 0.680851 (-6590 6160);
PAINT MONO (-6590 6160);
FORCEPROP 0 LASTPIN (-9600 6050) $PN W12
J 2
(-9610 6060);
DISPLAY 0.680851 (-9610 6060);
PAINT MONO (-9610 6060);
FORCEPROP 0 LASTPIN (-6600 5850) $PN W20
J 0
(-6590 5860);
DISPLAY 0.680851 (-6590 5860);
PAINT MONO (-6590 5860);
FORCEPROP 0 LASTPIN (-9600 6150) $PN W11
J 2
(-9610 6160);
DISPLAY 0.680851 (-9610 6160);
PAINT MONO (-9610 6160);
FORCEPROP 0 LASTPIN (-6600 5950) $PN W19
J 0
(-6590 5960);
DISPLAY 0.680851 (-6590 5960);
PAINT MONO (-6590 5960);
FORCEPROP 0 LASTPIN (-9600 5850) $PN V14
J 2
(-9610 5860);
DISPLAY 0.680851 (-9610 5860);
PAINT MONO (-9610 5860);
FORCEPROP 0 LASTPIN (-6600 5650) $PN Y19
J 0
(-6590 5660);
DISPLAY 0.680851 (-6590 5660);
PAINT MONO (-6590 5660);
FORCEPROP 0 LASTPIN (-9600 5950) $PN V13
J 2
(-9610 5960);
DISPLAY 0.680851 (-9610 5960);
PAINT MONO (-9610 5960);
FORCEPROP 0 LASTPIN (-6600 5750) $PN Y18
J 0
(-6590 5760);
DISPLAY 0.680851 (-6590 5760);
PAINT MONO (-6590 5760);
FORCEPROP 0 LASTPIN (-9600 5650) $PN V15
J 2
(-9610 5660);
DISPLAY 0.680851 (-9610 5660);
PAINT MONO (-9610 5660);
FORCEPROP 0 LASTPIN (-6600 5450) $PN V19
J 0
(-6590 5460);
DISPLAY 0.680851 (-6590 5460);
PAINT MONO (-6590 5460);
FORCEPROP 0 LASTPIN (-9600 5750) $PN U15
J 2
(-9610 5760);
DISPLAY 0.680851 (-9610 5760);
PAINT MONO (-9610 5760);
FORCEPROP 0 LASTPIN (-6600 5550) $PN V18
J 0
(-6590 5560);
DISPLAY 0.680851 (-6590 5560);
PAINT MONO (-6590 5560);
FORCEPROP 0 LASTPIN (-9600 5450) $PN T15
J 2
(-9610 5460);
DISPLAY 0.680851 (-9610 5460);
PAINT MONO (-9610 5460);
FORCEPROP 0 LASTPIN (-6600 5250) $PN AB20
J 0
(-6590 5260);
DISPLAY 0.680851 (-6590 5260);
PAINT MONO (-6590 5260);
FORCEPROP 0 LASTPIN (-9600 5550) $PN T14
J 2
(-9610 5560);
DISPLAY 0.680851 (-9610 5560);
PAINT MONO (-9610 5560);
FORCEPROP 0 LASTPIN (-6600 5350) $PN AA19
J 0
(-6590 5360);
DISPLAY 0.680851 (-6590 5360);
PAINT MONO (-6590 5360);
FORCEPROP 0 LASTPIN (-9600 5250) $PN W16
J 2
(-9610 5260);
DISPLAY 0.680851 (-9610 5260);
PAINT MONO (-9610 5260);
FORCEPROP 0 LASTPIN (-6600 5050) $PN W17
J 0
(-6590 5060);
DISPLAY 0.680851 (-6590 5060);
PAINT MONO (-6590 5060);
FORCEPROP 0 LASTPIN (-9600 5350) $PN W15
J 2
(-9610 5360);
DISPLAY 0.680851 (-9610 5360);
PAINT MONO (-9610 5360);
FORCEPROP 0 LASTPIN (-6600 5150) $PN V17
J 0
(-6590 5160);
DISPLAY 0.680851 (-6590 5160);
PAINT MONO (-6590 5160);
FORCEPROP 0 LASTPIN (-9600 5050) $PN U16
J 2
(-9610 5060);
DISPLAY 0.680851 (-9610 5060);
PAINT MONO (-9610 5060);
FORCEPROP 0 LASTPIN (-6600 4850) $PN AB18
J 0
(-6590 4860);
DISPLAY 0.680851 (-6590 4860);
PAINT MONO (-6590 4860);
FORCEPROP 0 LASTPIN (-9600 5150) $PN T16
J 2
(-9610 5160);
DISPLAY 0.680851 (-9610 5160);
PAINT MONO (-9610 5160);
FORCEPROP 0 LASTPIN (-6600 4950) $PN AA18
J 0
(-6590 4960);
DISPLAY 0.680851 (-6590 4960);
PAINT MONO (-6590 4960);
FORCEPROP 0 LASTPIN (-6600 4650) $PN U18
J 0
(-6590 4660);
DISPLAY 0.680851 (-6590 4660);
PAINT MONO (-6590 4660);
FORCEPROP 0 LASTPIN (-6600 4750) $PN U17
J 0
(-6590 4760);
DISPLAY 0.680851 (-6590 4760);
PAINT MONO (-6590 4760);
FORCEPROP 0 LASTPIN (-6600 4450) $PN R14
J 0
(-6590 4460);
DISPLAY 0.680851 (-6590 4460);
PAINT MONO (-6590 4460);
FORCEPROP 0 LASTPIN (-6600 4550) $PN P14
J 0
(-6590 4560);
DISPLAY 0.680851 (-6590 4560);
PAINT MONO (-6590 4560);
FORCEPROP 0 LASTPIN (-6600 4250) $PN T18
J 0
(-6590 4260);
DISPLAY 0.680851 (-6590 4260);
PAINT MONO (-6590 4260);
FORCEPROP 0 LASTPIN (-6600 4350) $PN R18
J 0
(-6590 4360);
DISPLAY 0.680851 (-6590 4360);
PAINT MONO (-6590 4360);
FORCEPROP 0 LASTPIN (-6600 4050) $PN P17
J 0
(-6590 4060);
DISPLAY 0.680851 (-6590 4060);
PAINT MONO (-6590 4060);
FORCEPROP 0 LASTPIN (-6600 4150) $PN N17
J 0
(-6590 4160);
DISPLAY 0.680851 (-6590 4160);
PAINT MONO (-6590 4160);
FORCEPROP 0 LASTPIN (-6600 3850) $PN R16
J 0
(-6590 3860);
DISPLAY 0.680851 (-6590 3860);
PAINT MONO (-6590 3860);
FORCEPROP 0 LASTPIN (-6600 3950) $PN P15
J 0
(-6590 3960);
DISPLAY 0.680851 (-6590 3960);
PAINT MONO (-6590 3960);
FORCEPROP 0 LASTPIN (-6600 3650) $PN N14
J 0
(-6590 3660);
DISPLAY 0.680851 (-6590 3660);
PAINT MONO (-6590 3660);
FORCEPROP 0 LASTPIN (-6600 3750) $PN N13
J 0
(-6590 3760);
DISPLAY 0.680851 (-6590 3760);
PAINT MONO (-6590 3760);
FORCEPROP 0 LASTPIN (-6600 3450) $PN R17
J 0
(-6590 3460);
DISPLAY 0.680851 (-6590 3460);
PAINT MONO (-6590 3460);
FORCEPROP 0 LASTPIN (-6600 3550) $PN P16
J 0
(-6590 3560);
DISPLAY 0.680851 (-6590 3560);
PAINT MONO (-6590 3560);
FORCEPROP 1 LAST CLS_PN G240-10069-01
J 0
(-9450 8850);
DISPLAY 1.212766 (-9450 8850);
PAINT GREEN (-9450 8850);
FORCEPROP 2 LAST CDS_LIB pld
J 0
(-9500 8650);
DISPLAY INVISIBLE (-9500 8650);
FORCEPROP 1 LAST CDS_LMAN_SYM_OUTLINE 0,0,2800,-5400
J 0
(-9500 8650);
DISPLAY 0.468085 (-9500 8650);
PAINT GREEN (-9500 8650);
DISPLAY INVISIBLE (-9500 8650);
FORCEPROP 1 LAST PATH I2
J 0
(-9450 8700);
DISPLAY 1.212766 (-9450 8700);
PAINT GREEN (-9450 8700);
DISPLAY INVISIBLE (-9450 8700);
FORCEADD RESISTOR..2
R 1
(-12600 7200);
FORCEPROP 1 LAST LOCATION R271
J 0
(-12950 7200);
DISPLAY 1.212766 (-12950 7200);
PAINT GREEN (-12950 7200);
FORCEPROP 0 LAST $SEC 1
R 1
J 0
(-12350 7300);
DISPLAY 0.680851 (-12350 7300);
PAINT MONO (-12350 7300);
DISPLAY INVISIBLE (-12350 7300);
FORCEPROP 0 LAST CDS_SEC 1
R 1
J 0
(-12350 7300);
DISPLAY 1.021277 (-12350 7300);
DISPLAY INVISIBLE (-12350 7300);
FORCEPROP 0 LASTPIN (-12700 7200) $PN 1
J 2
(-12710 7210);
DISPLAY 0.680851 (-12710 7210);
PAINT MONO (-12710 7210);
FORCEPROP 0 LASTPIN (-12450 7200) $PN 2
J 0
(-12440 7210);
DISPLAY 0.680851 (-12440 7210);
PAINT MONO (-12440 7210);
FORCEPROP 1 LAST VALUE 4.7KOHM
J 0
(-12350 7200);
DISPLAY 1.212766 (-12350 7200);
PAINT GREEN (-12350 7200);
FORCEPROP 0 LAST PACKAGE 0402
J 0
(-12650 7100);
DISPLAY 1.021277 (-12650 7100);
FORCEPROP 0 LAST NO_ASSY TRUE
J 0
(-13550 7200);
DISPLAY 0.808511 (-13550 7200);
DISPLAY BOTH (-13550 7200);
FORCEPROP 1 LAST PATH I200
R 1
J 0
(-12705 7003);
DISPLAY 1.212766 (-12705 7003);
PAINT GREEN (-12705 7003);
DISPLAY INVISIBLE (-12705 7003);
FORCEPROP 1 LAST TOLERANCE 1%
R 1
J 0
(-12855 7003);
DISPLAY 1.212766 (-12855 7003);
PAINT GREEN (-12855 7003);
DISPLAY INVISIBLE (-12855 7003);
FORCEPROP 1 LAST CLS_PN G155-14701-01
R 1
J 0
(-12800 7064);
DISPLAY 1.212766 (-12800 7064);
PAINT GREEN (-12800 7064);
DISPLAY INVISIBLE (-12800 7064);
FORCEPROP 1 LAST CDS_LMAN_SYM_OUTLINE -50,50,50,-100
R 1
J 0
(-12600 7200);
DISPLAY 0.468085 (-12600 7200);
PAINT GREEN (-12600 7200);
DISPLAY INVISIBLE (-12600 7200);
FORCEPROP 2 LAST CDS_LIB passive
J 0
(-12600 7200);
DISPLAY INVISIBLE (-12600 7200);
FORCEADD RESISTOR..2
R 1
(-12600 6900);
FORCEPROP 1 LAST LOCATION R288
J 0
(-12950 6900);
DISPLAY 1.212766 (-12950 6900);
PAINT GREEN (-12950 6900);
FORCEPROP 0 LAST $SEC 1
R 1
J 0
(-12350 7000);
DISPLAY 0.680851 (-12350 7000);
PAINT MONO (-12350 7000);
DISPLAY INVISIBLE (-12350 7000);
FORCEPROP 0 LAST CDS_SEC 1
R 1
J 0
(-12350 7000);
DISPLAY 1.021277 (-12350 7000);
DISPLAY INVISIBLE (-12350 7000);
FORCEPROP 0 LASTPIN (-12700 6900) $PN 1
J 2
(-12710 6910);
DISPLAY 0.680851 (-12710 6910);
PAINT MONO (-12710 6910);
FORCEPROP 0 LASTPIN (-12450 6900) $PN 2
J 0
(-12440 6910);
DISPLAY 0.680851 (-12440 6910);
PAINT MONO (-12440 6910);
FORCEPROP 1 LAST VALUE 4.7KOHM
J 0
(-12350 6900);
DISPLAY 1.212766 (-12350 6900);
PAINT GREEN (-12350 6900);
FORCEPROP 0 LAST PACKAGE 0402
J 0
(-12650 6950);
DISPLAY 1.021277 (-12650 6950);
FORCEPROP 1 LAST CLS_PN G155-14701-01
R 1
J 0
(-12800 6764);
DISPLAY 1.212766 (-12800 6764);
PAINT GREEN (-12800 6764);
DISPLAY INVISIBLE (-12800 6764);
FORCEPROP 1 LAST TOLERANCE 1%
R 1
J 0
(-12855 6703);
DISPLAY 1.212766 (-12855 6703);
PAINT GREEN (-12855 6703);
DISPLAY INVISIBLE (-12855 6703);
FORCEPROP 1 LAST PATH I201
R 1
J 0
(-12705 6703);
DISPLAY 1.212766 (-12705 6703);
PAINT GREEN (-12705 6703);
DISPLAY INVISIBLE (-12705 6703);
FORCEPROP 1 LAST CDS_LMAN_SYM_OUTLINE -50,50,50,-100
R 1
J 0
(-12600 6900);
DISPLAY 0.468085 (-12600 6900);
PAINT GREEN (-12600 6900);
DISPLAY INVISIBLE (-12600 6900);
FORCEPROP 2 LAST CDS_LIB passive
J 0
(-12600 6900);
DISPLAY INVISIBLE (-12600 6900);
FORCEADD OFFPAGE_IN..2
(-4650 6650);
FORCEPROP 2 LAST $XR0 23G11> 
J 0
(-4595 6650);
DISPLAY 0.638298 (-4595 6650);
PAINT MONO (-4595 6650);
FORCEPROP 2 LAST PATH I208
J 0
(-4600 6750);
DISPLAY 1.021277 (-4600 6750);
DISPLAY INVISIBLE (-4600 6750);
FORCEPROP 1 LAST OFFPAGE TRUE
J 0
(-4640 6705);
DISPLAY 0.808511 (-4640 6705);
PAINT GREEN (-4640 6705);
DISPLAY INVISIBLE (-4640 6705);
FORCEPROP 2 LAST CDS_LIB cls
J 0
(-4650 6650);
DISPLAY INVISIBLE (-4650 6650);
FORCEPROP 1 LAST CDS_LMAN_SYM_OUTLINE -50,50,50,-50
J 0
(-4650 6650);
DISPLAY 0.468085 (-4650 6650);
PAINT GREEN (-4650 6650);
DISPLAY INVISIBLE (-4650 6650);
FORCEPROP 1 LAST BODY_TYPE COMMENT
J 0
(-4640 6785);
DISPLAY 0.808511 (-4640 6785);
PAINT GREEN (-4640 6785);
DISPLAY INVISIBLE (-4640 6785);
FORCEADD OFFPAGE_IN..2
(-4650 6750);
FORCEPROP 2 LAST $XR0 23J11> 
J 0
(-4595 6750);
DISPLAY 0.638298 (-4595 6750);
PAINT MONO (-4595 6750);
FORCEPROP 2 LAST $XR1 ?
J 0
(-4385 6750);
DISPLAY 0.638298 (-4385 6750);
PAINT MONO (-4385 6750);
FORCEPROP 2 LAST PATH I209
J 0
(-4600 6850);
DISPLAY 1.021277 (-4600 6850);
DISPLAY INVISIBLE (-4600 6850);
FORCEPROP 1 LAST OFFPAGE TRUE
J 0
(-4640 6805);
DISPLAY 0.808511 (-4640 6805);
PAINT GREEN (-4640 6805);
DISPLAY INVISIBLE (-4640 6805);
FORCEPROP 2 LAST CDS_LIB cls
J 0
(-4650 6750);
DISPLAY INVISIBLE (-4650 6750);
FORCEPROP 1 LAST CDS_LMAN_SYM_OUTLINE -50,50,50,-50
J 0
(-4650 6750);
DISPLAY 0.468085 (-4650 6750);
PAINT GREEN (-4650 6750);
DISPLAY INVISIBLE (-4650 6750);
FORCEPROP 1 LAST BODY_TYPE COMMENT
J 0
(-4640 6885);
DISPLAY 0.808511 (-4640 6885);
PAINT GREEN (-4640 6885);
DISPLAY INVISIBLE (-4640 6885);
FORCEADD OFFPAGE_BI..1
(-4650 5950);
FORCEPROP 2 LAST $XR0 26J2<> 
J 0
(-4590 5950);
DISPLAY 0.638298 (-4590 5950);
PAINT MONO (-4590 5950);
FORCEPROP 2 LAST PATH I224
J 0
(-4600 6050);
DISPLAY 1.021277 (-4600 6050);
DISPLAY INVISIBLE (-4600 6050);
FORCEPROP 1 LAST OFFPAGE TRUE
J 0
(-4640 6005);
DISPLAY 0.808511 (-4640 6005);
PAINT GREEN (-4640 6005);
DISPLAY INVISIBLE (-4640 6005);
FORCEPROP 2 LAST CDS_LIB cls
J 0
(-4650 5950);
DISPLAY INVISIBLE (-4650 5950);
FORCEPROP 1 LAST CDS_LMAN_SYM_OUTLINE -50,50,50,-50
J 0
(-4650 5950);
DISPLAY 0.468085 (-4650 5950);
PAINT GREEN (-4650 5950);
DISPLAY INVISIBLE (-4650 5950);
FORCEPROP 1 LAST BODY_TYPE COMMENT
J 0
(-4640 6085);
DISPLAY 0.808511 (-4640 6085);
PAINT GREEN (-4640 6085);
DISPLAY INVISIBLE (-4640 6085);
FORCEADD OFFPAGE_OUT..1
(-4650 5850);
FORCEPROP 2 LAST $XR0 26K2< 
J 0
(-4595 5850);
DISPLAY 0.638298 (-4595 5850);
PAINT MONO (-4595 5850);
FORCEPROP 2 LAST PATH I225
J 0
(-4600 5950);
DISPLAY 1.021277 (-4600 5950);
DISPLAY INVISIBLE (-4600 5950);
FORCEPROP 1 LAST OFFPAGE TRUE
J 0
(-4640 5905);
DISPLAY 0.808511 (-4640 5905);
PAINT GREEN (-4640 5905);
DISPLAY INVISIBLE (-4640 5905);
FORCEPROP 1 LAST BODY_TYPE COMMENT
J 0
(-4640 5985);
DISPLAY 0.808511 (-4640 5985);
PAINT GREEN (-4640 5985);
DISPLAY INVISIBLE (-4640 5985);
FORCEPROP 1 LAST CDS_LMAN_SYM_OUTLINE -50,50,50,-50
J 0
(-4650 5850);
DISPLAY 0.468085 (-4650 5850);
PAINT GREEN (-4650 5850);
DISPLAY INVISIBLE (-4650 5850);
FORCEPROP 2 LAST CDS_LIB cls
J 0
(-4650 5850);
DISPLAY INVISIBLE (-4650 5850);
FORCEADD OFFPAGE_OUT..1
(-4650 5750);
FORCEPROP 2 LAST $XR0 26K2< 
J 0
(-4595 5750);
DISPLAY 0.638298 (-4595 5750);
PAINT MONO (-4595 5750);
FORCEPROP 2 LAST PATH I226
J 0
(-4600 5850);
DISPLAY 1.021277 (-4600 5850);
DISPLAY INVISIBLE (-4600 5850);
FORCEPROP 1 LAST OFFPAGE TRUE
J 0
(-4640 5805);
DISPLAY 0.808511 (-4640 5805);
PAINT GREEN (-4640 5805);
DISPLAY INVISIBLE (-4640 5805);
FORCEPROP 2 LAST CDS_LIB cls
J 0
(-4650 5750);
DISPLAY INVISIBLE (-4650 5750);
FORCEPROP 1 LAST CDS_LMAN_SYM_OUTLINE -50,50,50,-50
J 0
(-4650 5750);
DISPLAY 0.468085 (-4650 5750);
PAINT GREEN (-4650 5750);
DISPLAY INVISIBLE (-4650 5750);
FORCEPROP 1 LAST BODY_TYPE COMMENT
J 0
(-4640 5885);
DISPLAY 0.808511 (-4640 5885);
PAINT GREEN (-4640 5885);
DISPLAY INVISIBLE (-4640 5885);
FORCEADD OFFPAGE_BI..1
R 4
(-11400 7750);
FORCEPROP 2 LAST $XR0 24K5<> 
J 0
(-11619 7750);
DISPLAY 0.638298 (-11619 7750);
PAINT MONO (-11619 7750);
FORCEPROP 1 LAST BODY_TYPE COMMENT
R 2
J 0
(-11410 7615);
DISPLAY 0.808511 (-11410 7615);
PAINT GREEN (-11410 7615);
DISPLAY INVISIBLE (-11410 7615);
FORCEPROP 1 LAST OFFPAGE TRUE
R 2
J 0
(-11410 7695);
DISPLAY 0.808511 (-11410 7695);
PAINT GREEN (-11410 7695);
DISPLAY INVISIBLE (-11410 7695);
FORCEPROP 1 LAST CDS_LMAN_SYM_OUTLINE -50,50,50,-50
R 2
J 0
(-11400 7750);
DISPLAY 0.468085 (-11400 7750);
PAINT GREEN (-11400 7750);
DISPLAY INVISIBLE (-11400 7750);
FORCEPROP 2 LAST CDS_LIB cls
J 0
(-11400 7750);
DISPLAY INVISIBLE (-11400 7750);
FORCEPROP 2 LAST PATH I234
J 0
(-11600 7800);
DISPLAY 1.021277 (-11600 7800);
DISPLAY INVISIBLE (-11600 7800);
FORCEADD OFFPAGE_OUT..1
R 2
(-11400 7850);
FORCEPROP 2 LAST $XR0 16K4< 
J 0
(-11583 7850);
DISPLAY 0.638298 (-11583 7850);
PAINT MONO (-11583 7850);
FORCEPROP 1 LAST BODY_TYPE COMMENT
J 2
(-11410 7985);
DISPLAY 0.808511 (-11410 7985);
PAINT GREEN (-11410 7985);
DISPLAY INVISIBLE (-11410 7985);
FORCEPROP 1 LAST OFFPAGE TRUE
J 2
(-11410 7905);
DISPLAY 0.808511 (-11410 7905);
PAINT GREEN (-11410 7905);
DISPLAY INVISIBLE (-11410 7905);
FORCEPROP 1 LAST CDS_LMAN_SYM_OUTLINE -50,50,50,-50
J 2
(-11400 7850);
DISPLAY 0.468085 (-11400 7850);
PAINT GREEN (-11400 7850);
DISPLAY INVISIBLE (-11400 7850);
FORCEPROP 2 LAST PATH I235
J 0
(-11350 7950);
DISPLAY 1.021277 (-11350 7950);
DISPLAY INVISIBLE (-11350 7950);
FORCEPROP 2 LAST CDS_LIB cls
J 0
(-11400 7850);
DISPLAY INVISIBLE (-11400 7850);
FORCEADD OFFPAGE_OUT..1
R 2
(-11400 6050);
FORCEPROP 2 LAST $XR0 23E3< 
J 0
(-11583 6050);
DISPLAY 0.638298 (-11583 6050);
PAINT MONO (-11583 6050);
FORCEPROP 2 LAST CDS_LIB cls
J 0
(-11400 6050);
DISPLAY INVISIBLE (-11400 6050);
FORCEPROP 2 LAST PATH I236
J 0
(-11350 6150);
DISPLAY 1.021277 (-11350 6150);
DISPLAY INVISIBLE (-11350 6150);
FORCEPROP 1 LAST CDS_LMAN_SYM_OUTLINE -50,50,50,-50
J 2
(-11400 6050);
DISPLAY 0.468085 (-11400 6050);
PAINT GREEN (-11400 6050);
DISPLAY INVISIBLE (-11400 6050);
FORCEPROP 1 LAST BODY_TYPE COMMENT
J 2
(-11410 6185);
DISPLAY 0.808511 (-11410 6185);
PAINT GREEN (-11410 6185);
DISPLAY INVISIBLE (-11410 6185);
FORCEPROP 1 LAST OFFPAGE TRUE
J 2
(-11410 6105);
DISPLAY 0.808511 (-11410 6105);
PAINT GREEN (-11410 6105);
DISPLAY INVISIBLE (-11410 6105);
FORCEADD OFFPAGE_OUT..1
R 2
(-11400 6150);
FORCEPROP 2 LAST $XR0 23C3< 
J 0
(-11583 6150);
DISPLAY 0.638298 (-11583 6150);
PAINT MONO (-11583 6150);
FORCEPROP 2 LAST CDS_LIB cls
J 0
(-11400 6150);
DISPLAY INVISIBLE (-11400 6150);
FORCEPROP 2 LAST PATH I237
J 0
(-11350 6250);
DISPLAY 1.021277 (-11350 6250);
DISPLAY INVISIBLE (-11350 6250);
FORCEPROP 1 LAST CDS_LMAN_SYM_OUTLINE -50,50,50,-50
J 2
(-11400 6150);
DISPLAY 0.468085 (-11400 6150);
PAINT GREEN (-11400 6150);
DISPLAY INVISIBLE (-11400 6150);
FORCEPROP 1 LAST BODY_TYPE COMMENT
J 2
(-11410 6285);
DISPLAY 0.808511 (-11410 6285);
PAINT GREEN (-11410 6285);
DISPLAY INVISIBLE (-11410 6285);
FORCEPROP 1 LAST OFFPAGE TRUE
J 2
(-11410 6205);
DISPLAY 0.808511 (-11410 6205);
PAINT GREEN (-11410 6205);
DISPLAY INVISIBLE (-11410 6205);
FORCEADD GND_SG..1
(-3000 4250);
FORCEPROP 3 LASTPIN (-2950 4300) SIG_NAME SG\g
J 0
(-2940 4310);
DISPLAY 0.659574 (-2940 4310);
PAINT MONO (-2940 4310);
DISPLAY INVISIBLE (-2940 4310);
FORCEPROP 1 LAST HDL_POWER SG
J 1
(-2945 4155);
DISPLAY 0.808511 (-2945 4155);
PAINT GREEN (-2945 4155);
FORCEPROP 2 LAST CDS_LIB cls
J 0
(-3000 4250);
DISPLAY INVISIBLE (-3000 4250);
FORCEPROP 1 LAST PATH I238
J 0
(-2965 4250);
DISPLAY 0.808511 (-2965 4250);
PAINT GREEN (-2965 4250);
DISPLAY INVISIBLE (-2965 4250);
FORCEPROP 1 LAST CDS_LMAN_SYM_OUTLINE 0,0,100,-50
J 0
(-3000 4250);
DISPLAY 0.468085 (-3000 4250);
PAINT GREEN (-3000 4250);
DISPLAY INVISIBLE (-3000 4250);
FORCEPROP 1 LAST BODY_TYPE PLUMBING
J 0
(-2985 4235);
DISPLAY 0.808511 (-2985 4235);
PAINT GREEN (-2985 4235);
DISPLAY INVISIBLE (-2985 4235);
FORCEADD RESISTOR..1
R 4
(-3650 4400);
FORCEPROP 1 LAST $LOCATION R437
J 2
(-3950 4400);
DISPLAY 1.212766 (-3950 4400);
PAINT GREEN (-3950 4400);
FORCEPROP 0 LAST CDS_LOCATION R437
J 0
(-3450 4500);
DISPLAY 1.021277 (-3450 4500);
DISPLAY INVISIBLE (-3450 4500);
FORCEPROP 0 LAST $SEC 1
J 0
(-3450 4500);
DISPLAY 0.680851 (-3450 4500);
PAINT MONO (-3450 4500);
DISPLAY INVISIBLE (-3450 4500);
FORCEPROP 0 LAST CDS_SEC 1
J 0
(-3450 4500);
DISPLAY 1.021277 (-3450 4500);
DISPLAY INVISIBLE (-3450 4500);
FORCEPROP 0 LASTPIN (-3550 4400) $PN 1
J 0
(-3540 4410);
DISPLAY 0.680851 (-3540 4410);
PAINT MONO (-3540 4410);
FORCEPROP 0 LASTPIN (-3800 4400) $PN 2
J 2
(-3810 4410);
DISPLAY 0.680851 (-3810 4410);
PAINT MONO (-3810 4410);
FORCEPROP 0 LAST NO_ASSY TRUE
J 0
(-3050 4450);
DISPLAY 0.808511 (-3050 4450);
DISPLAY BOTH (-3050 4450);
FORCEPROP 1 LAST VALUE 15KOHM
J 0
(-3450 4400);
DISPLAY 1.212766 (-3450 4400);
PAINT GREEN (-3450 4400);
FORCEPROP 0 LAST PACKAGE 0402
J 0
(-3750 4450);
DISPLAY 0.808511 (-3750 4450);
FORCEPROP 2 LAST CDS_LIB passive
J 0
(-3650 4400);
DISPLAY INVISIBLE (-3650 4400);
FORCEPROP 1 LAST PATH I239
R 2
J 0
(-3453 4295);
DISPLAY 1.212766 (-3453 4295);
PAINT GREEN (-3453 4295);
DISPLAY INVISIBLE (-3453 4295);
FORCEPROP 1 LAST CDS_LMAN_SYM_OUTLINE -50,50,100,-50
R 2
J 0
(-3650 4400);
DISPLAY 0.468085 (-3650 4400);
PAINT GREEN (-3650 4400);
DISPLAY INVISIBLE (-3650 4400);
FORCEPROP 1 LAST TOLERANCE 1%
R 2
J 0
(-3453 4145);
DISPLAY 1.212766 (-3453 4145);
PAINT GREEN (-3453 4145);
DISPLAY INVISIBLE (-3453 4145);
FORCEPROP 1 LAST CLS_PN G155-11502-01
R 2
J 0
(-3514 4200);
DISPLAY 1.212766 (-3514 4200);
PAINT GREEN (-3514 4200);
DISPLAY INVISIBLE (-3514 4200);
FORCEADD RESISTOR..1
R 4
(-3650 4500);
FORCEPROP 1 LAST $LOCATION R436
J 2
(-3950 4500);
DISPLAY 1.212766 (-3950 4500);
PAINT GREEN (-3950 4500);
FORCEPROP 0 LAST CDS_LOCATION R436
J 0
(-3750 4650);
DISPLAY 1.021277 (-3750 4650);
DISPLAY INVISIBLE (-3750 4650);
FORCEPROP 0 LAST $SEC 1
J 0
(-3750 4650);
DISPLAY 0.680851 (-3750 4650);
PAINT MONO (-3750 4650);
DISPLAY INVISIBLE (-3750 4650);
FORCEPROP 0 LAST CDS_SEC 1
J 0
(-3750 4650);
DISPLAY 1.021277 (-3750 4650);
DISPLAY INVISIBLE (-3750 4650);
FORCEPROP 0 LASTPIN (-3550 4500) $PN 1
J 0
(-3540 4510);
DISPLAY 0.680851 (-3540 4510);
PAINT MONO (-3540 4510);
FORCEPROP 0 LASTPIN (-3800 4500) $PN 2
J 2
(-3810 4510);
DISPLAY 0.680851 (-3810 4510);
PAINT MONO (-3810 4510);
FORCEPROP 0 LAST NO_ASSY TRUE
J 0
(-3050 4500);
DISPLAY 0.808511 (-3050 4500);
DISPLAY BOTH (-3050 4500);
FORCEPROP 1 LAST VALUE 15KOHM
J 0
(-3450 4500);
DISPLAY 1.212766 (-3450 4500);
PAINT GREEN (-3450 4500);
FORCEPROP 0 LAST PACKAGE 0402
J 0
(-3750 4550);
DISPLAY 0.808511 (-3750 4550);
FORCEPROP 2 LAST CDS_LIB passive
J 0
(-3650 4500);
DISPLAY INVISIBLE (-3650 4500);
FORCEPROP 1 LAST CDS_LMAN_SYM_OUTLINE -50,50,100,-50
R 2
J 0
(-3650 4500);
DISPLAY 0.468085 (-3650 4500);
PAINT GREEN (-3650 4500);
DISPLAY INVISIBLE (-3650 4500);
FORCEPROP 1 LAST TOLERANCE 1%
R 2
J 0
(-3453 4245);
DISPLAY 1.212766 (-3453 4245);
PAINT GREEN (-3453 4245);
DISPLAY INVISIBLE (-3453 4245);
FORCEPROP 1 LAST PATH I240
R 2
J 0
(-3453 4395);
DISPLAY 1.212766 (-3453 4395);
PAINT GREEN (-3453 4395);
DISPLAY INVISIBLE (-3453 4395);
FORCEPROP 1 LAST CLS_PN G155-11502-01
R 2
J 0
(-3514 4300);
DISPLAY 1.212766 (-3514 4300);
PAINT GREEN (-3514 4300);
DISPLAY INVISIBLE (-3514 4300);
FORCEADD RESISTOR..2
R 1
(-12550 6200);
FORCEPROP 1 LAST $LOCATION R501
J 0
(-12950 6200);
DISPLAY 1.212766 (-12950 6200);
PAINT GREEN (-12950 6200);
FORCEPROP 0 LAST CDS_LOCATION R501
R 1
J 0
(-12300 6300);
DISPLAY 1.021277 (-12300 6300);
DISPLAY INVISIBLE (-12300 6300);
FORCEPROP 0 LAST $SEC 1
R 1
J 0
(-12300 6300);
DISPLAY 0.680851 (-12300 6300);
PAINT MONO (-12300 6300);
DISPLAY INVISIBLE (-12300 6300);
FORCEPROP 0 LAST CDS_SEC 1
R 1
J 0
(-12300 6300);
DISPLAY 1.021277 (-12300 6300);
DISPLAY INVISIBLE (-12300 6300);
FORCEPROP 0 LASTPIN (-12650 6200) $PN 1
J 2
(-12660 6210);
DISPLAY 0.680851 (-12660 6210);
PAINT MONO (-12660 6210);
FORCEPROP 0 LASTPIN (-12400 6200) $PN 2
J 0
(-12390 6210);
DISPLAY 0.680851 (-12390 6210);
PAINT MONO (-12390 6210);
FORCEPROP 0 LAST NO_ASSY TRUE
J 0
(-13550 6200);
DISPLAY 0.808511 (-13550 6200);
DISPLAY BOTH (-13550 6200);
FORCEPROP 0 LAST PACKAGE 0402
J 0
(-12600 6100);
DISPLAY 1.021277 (-12600 6100);
FORCEPROP 1 LAST VALUE 4.7KOHM
J 0
(-12300 6200);
DISPLAY 1.212766 (-12300 6200);
PAINT GREEN (-12300 6200);
FORCEPROP 1 LAST PATH I241
R 1
J 0
(-12655 6003);
DISPLAY 1.212766 (-12655 6003);
PAINT GREEN (-12655 6003);
DISPLAY INVISIBLE (-12655 6003);
FORCEPROP 2 LAST CDS_LIB passive
J 0
(-12550 6200);
DISPLAY INVISIBLE (-12550 6200);
FORCEPROP 1 LAST CDS_LMAN_SYM_OUTLINE -50,50,50,-100
R 1
J 0
(-12550 6200);
DISPLAY 0.468085 (-12550 6200);
PAINT GREEN (-12550 6200);
DISPLAY INVISIBLE (-12550 6200);
FORCEPROP 1 LAST CLS_PN G155-14701-01
R 1
J 0
(-12750 6064);
DISPLAY 1.212766 (-12750 6064);
PAINT GREEN (-12750 6064);
DISPLAY INVISIBLE (-12750 6064);
FORCEPROP 1 LAST TOLERANCE 1%
R 1
J 0
(-12805 6003);
DISPLAY 1.212766 (-12805 6003);
PAINT GREEN (-12805 6003);
DISPLAY INVISIBLE (-12805 6003);
FORCEADD RESISTOR..2
R 1
(-12550 6300);
FORCEPROP 1 LAST $LOCATION R500
J 0
(-12950 6300);
DISPLAY 1.212766 (-12950 6300);
PAINT GREEN (-12950 6300);
FORCEPROP 0 LAST CDS_LOCATION R500
R 1
J 0
(-12300 6400);
DISPLAY 1.021277 (-12300 6400);
DISPLAY INVISIBLE (-12300 6400);
FORCEPROP 0 LAST $SEC 1
R 1
J 0
(-12300 6400);
DISPLAY 0.680851 (-12300 6400);
PAINT MONO (-12300 6400);
DISPLAY INVISIBLE (-12300 6400);
FORCEPROP 0 LAST CDS_SEC 1
R 1
J 0
(-12300 6400);
DISPLAY 1.021277 (-12300 6400);
DISPLAY INVISIBLE (-12300 6400);
FORCEPROP 0 LASTPIN (-12650 6300) $PN 1
J 2
(-12660 6310);
DISPLAY 0.680851 (-12660 6310);
PAINT MONO (-12660 6310);
FORCEPROP 0 LASTPIN (-12400 6300) $PN 2
J 0
(-12390 6310);
DISPLAY 0.680851 (-12390 6310);
PAINT MONO (-12390 6310);
FORCEPROP 1 LAST VALUE 4.7KOHM
J 0
(-12300 6300);
DISPLAY 1.212766 (-12300 6300);
PAINT GREEN (-12300 6300);
FORCEPROP 0 LAST PACKAGE 0402
J 0
(-12600 6350);
DISPLAY 1.021277 (-12600 6350);
FORCEPROP 0 LAST NO_ASSY TRUE
J 0
(-13550 6300);
DISPLAY 0.808511 (-13550 6300);
DISPLAY BOTH (-13550 6300);
FORCEPROP 1 LAST PATH I242
R 1
J 0
(-12655 6103);
DISPLAY 1.212766 (-12655 6103);
PAINT GREEN (-12655 6103);
DISPLAY INVISIBLE (-12655 6103);
FORCEPROP 1 LAST TOLERANCE 1%
R 1
J 0
(-12805 6103);
DISPLAY 1.212766 (-12805 6103);
PAINT GREEN (-12805 6103);
DISPLAY INVISIBLE (-12805 6103);
FORCEPROP 1 LAST CLS_PN G155-14701-01
R 1
J 0
(-12750 6164);
DISPLAY 1.212766 (-12750 6164);
PAINT GREEN (-12750 6164);
DISPLAY INVISIBLE (-12750 6164);
FORCEPROP 1 LAST CDS_LMAN_SYM_OUTLINE -50,50,50,-100
R 1
J 0
(-12550 6300);
DISPLAY 0.468085 (-12550 6300);
PAINT GREEN (-12550 6300);
DISPLAY INVISIBLE (-12550 6300);
FORCEPROP 2 LAST CDS_LIB passive
J 0
(-12550 6300);
DISPLAY INVISIBLE (-12550 6300);
FORCEADD RESISTOR..2
R 1
(-3850 6600);
FORCEPROP 1 LAST $LOCATION R504
J 0
(-4200 6600);
DISPLAY 1.212766 (-4200 6600);
PAINT GREEN (-4200 6600);
FORCEPROP 0 LAST CDS_LOCATION R504
R 1
J 0
(-3650 6700);
DISPLAY 1.021277 (-3650 6700);
DISPLAY INVISIBLE (-3650 6700);
FORCEPROP 0 LAST $SEC 1
R 1
J 0
(-3650 6700);
DISPLAY 0.680851 (-3650 6700);
PAINT MONO (-3650 6700);
DISPLAY INVISIBLE (-3650 6700);
FORCEPROP 0 LAST CDS_SEC 1
R 1
J 0
(-3650 6700);
DISPLAY 1.021277 (-3650 6700);
DISPLAY INVISIBLE (-3650 6700);
FORCEPROP 0 LASTPIN (-3950 6600) $PN 1
J 2
(-3960 6610);
DISPLAY 0.680851 (-3960 6610);
PAINT MONO (-3960 6610);
FORCEPROP 0 LASTPIN (-3700 6600) $PN 2
J 0
(-3690 6610);
DISPLAY 0.680851 (-3690 6610);
PAINT MONO (-3690 6610);
FORCEPROP 0 LAST NO_ASSY TRUE
J 0
(-3100 6600);
DISPLAY 0.808511 (-3100 6600);
DISPLAY BOTH (-3100 6600);
FORCEPROP 1 LAST VALUE 4.7KOHM
J 0
(-3650 6600);
DISPLAY 1.212766 (-3650 6600);
PAINT GREEN (-3650 6600);
FORCEPROP 0 LAST PACKAGE 0402
J 0
(-3900 6500);
DISPLAY 1.021277 (-3900 6500);
FORCEPROP 2 LAST CDS_LIB passive
J 0
(-3850 6600);
DISPLAY INVISIBLE (-3850 6600);
FORCEPROP 1 LAST CDS_LMAN_SYM_OUTLINE -50,50,50,-100
R 1
J 0
(-3850 6600);
DISPLAY 0.468085 (-3850 6600);
PAINT GREEN (-3850 6600);
DISPLAY INVISIBLE (-3850 6600);
FORCEPROP 1 LAST CLS_PN G155-14701-01
R 1
J 0
(-4050 6464);
DISPLAY 1.212766 (-4050 6464);
PAINT GREEN (-4050 6464);
DISPLAY INVISIBLE (-4050 6464);
FORCEPROP 1 LAST TOLERANCE 1%
R 1
J 0
(-4105 6403);
DISPLAY 1.212766 (-4105 6403);
PAINT GREEN (-4105 6403);
DISPLAY INVISIBLE (-4105 6403);
FORCEPROP 1 LAST PATH I244
R 1
J 0
(-3955 6403);
DISPLAY 1.212766 (-3955 6403);
PAINT GREEN (-3955 6403);
DISPLAY INVISIBLE (-3955 6403);
FORCEADD GND_SG..1
(-3200 6450);
FORCEPROP 3 LASTPIN (-3150 6500) SIG_NAME SG\g
J 0
(-3140 6510);
DISPLAY 0.659574 (-3140 6510);
PAINT MONO (-3140 6510);
DISPLAY INVISIBLE (-3140 6510);
FORCEPROP 1 LAST HDL_POWER SG
J 1
(-3145 6355);
DISPLAY 0.808511 (-3145 6355);
PAINT GREEN (-3145 6355);
FORCEPROP 1 LAST BODY_TYPE PLUMBING
J 0
(-3185 6435);
DISPLAY 0.808511 (-3185 6435);
PAINT GREEN (-3185 6435);
DISPLAY INVISIBLE (-3185 6435);
FORCEPROP 2 LAST CDS_LIB cls
J 0
(-3200 6450);
DISPLAY INVISIBLE (-3200 6450);
FORCEPROP 1 LAST CDS_LMAN_SYM_OUTLINE 0,0,100,-50
J 0
(-3200 6450);
DISPLAY 0.468085 (-3200 6450);
PAINT GREEN (-3200 6450);
DISPLAY INVISIBLE (-3200 6450);
FORCEPROP 1 LAST PATH I245
J 0
(-3165 6450);
DISPLAY 0.808511 (-3165 6450);
PAINT GREEN (-3165 6450);
DISPLAY INVISIBLE (-3165 6450);
FORCEADD RESISTOR..2
R 1
(-3850 6700);
FORCEPROP 1 LAST $LOCATION R503
J 0
(-4200 6700);
DISPLAY 1.212766 (-4200 6700);
PAINT GREEN (-4200 6700);
FORCEPROP 0 LAST CDS_LOCATION R503
R 1
J 0
(-3650 6800);
DISPLAY 1.021277 (-3650 6800);
DISPLAY INVISIBLE (-3650 6800);
FORCEPROP 0 LAST $SEC 1
R 1
J 0
(-3650 6800);
DISPLAY 0.680851 (-3650 6800);
PAINT MONO (-3650 6800);
DISPLAY INVISIBLE (-3650 6800);
FORCEPROP 0 LAST CDS_SEC 1
R 1
J 0
(-3650 6800);
DISPLAY 1.021277 (-3650 6800);
DISPLAY INVISIBLE (-3650 6800);
FORCEPROP 0 LASTPIN (-3950 6700) $PN 1
J 2
(-3960 6710);
DISPLAY 0.680851 (-3960 6710);
PAINT MONO (-3960 6710);
FORCEPROP 0 LASTPIN (-3700 6700) $PN 2
J 0
(-3690 6710);
DISPLAY 0.680851 (-3690 6710);
PAINT MONO (-3690 6710);
FORCEPROP 0 LAST NO_ASSY TRUE
J 0
(-3100 6700);
DISPLAY 0.808511 (-3100 6700);
DISPLAY BOTH (-3100 6700);
FORCEPROP 1 LAST VALUE 4.7KOHM
J 0
(-3650 6700);
DISPLAY 1.212766 (-3650 6700);
PAINT GREEN (-3650 6700);
FORCEPROP 0 LAST PACKAGE 0402
J 0
(-3900 6750);
DISPLAY 1.021277 (-3900 6750);
FORCEPROP 1 LAST PATH I246
R 1
J 0
(-3955 6503);
DISPLAY 1.212766 (-3955 6503);
PAINT GREEN (-3955 6503);
DISPLAY INVISIBLE (-3955 6503);
FORCEPROP 2 LAST CDS_LIB passive
J 0
(-3850 6700);
DISPLAY INVISIBLE (-3850 6700);
FORCEPROP 1 LAST CDS_LMAN_SYM_OUTLINE -50,50,50,-100
R 1
J 0
(-3850 6700);
DISPLAY 0.468085 (-3850 6700);
PAINT GREEN (-3850 6700);
DISPLAY INVISIBLE (-3850 6700);
FORCEPROP 1 LAST CLS_PN G155-14701-01
R 1
J 0
(-4050 6564);
DISPLAY 1.212766 (-4050 6564);
PAINT GREEN (-4050 6564);
DISPLAY INVISIBLE (-4050 6564);
FORCEPROP 1 LAST TOLERANCE 1%
R 1
J 0
(-4105 6503);
DISPLAY 1.212766 (-4105 6503);
PAINT GREEN (-4105 6503);
DISPLAY INVISIBLE (-4105 6503);
FORCEADD RESISTOR..2
R 1
(-12550 5900);
FORCEPROP 1 LAST $LOCATION R502
J 0
(-12950 5900);
DISPLAY 1.212766 (-12950 5900);
PAINT GREEN (-12950 5900);
FORCEPROP 0 LAST CDS_LOCATION R502
R 1
J 0
(-12300 6000);
DISPLAY 1.021277 (-12300 6000);
DISPLAY INVISIBLE (-12300 6000);
FORCEPROP 0 LAST $SEC 1
R 1
J 0
(-12300 6000);
DISPLAY 0.680851 (-12300 6000);
PAINT MONO (-12300 6000);
DISPLAY INVISIBLE (-12300 6000);
FORCEPROP 0 LAST CDS_SEC 1
R 1
J 0
(-12300 6000);
DISPLAY 1.021277 (-12300 6000);
DISPLAY INVISIBLE (-12300 6000);
FORCEPROP 0 LASTPIN (-12650 5900) $PN 1
J 2
(-12660 5910);
DISPLAY 0.680851 (-12660 5910);
PAINT MONO (-12660 5910);
FORCEPROP 0 LASTPIN (-12400 5900) $PN 2
J 0
(-12390 5910);
DISPLAY 0.680851 (-12390 5910);
PAINT MONO (-12390 5910);
FORCEPROP 1 LAST VALUE 4.7KOHM
J 0
(-12300 5900);
DISPLAY 1.212766 (-12300 5900);
PAINT GREEN (-12300 5900);
FORCEPROP 0 LAST PACKAGE 0402
J 0
(-12600 5950);
DISPLAY 1.021277 (-12600 5950);
FORCEPROP 1 LAST CLS_PN G155-14701-01
R 1
J 0
(-12750 5764);
DISPLAY 1.212766 (-12750 5764);
PAINT GREEN (-12750 5764);
DISPLAY INVISIBLE (-12750 5764);
FORCEPROP 1 LAST TOLERANCE 1%
R 1
J 0
(-12805 5703);
DISPLAY 1.212766 (-12805 5703);
PAINT GREEN (-12805 5703);
DISPLAY INVISIBLE (-12805 5703);
FORCEPROP 1 LAST CDS_LMAN_SYM_OUTLINE -50,50,50,-100
R 1
J 0
(-12550 5900);
DISPLAY 0.468085 (-12550 5900);
PAINT GREEN (-12550 5900);
DISPLAY INVISIBLE (-12550 5900);
FORCEPROP 1 LAST PATH I247
R 1
J 0
(-12655 5703);
DISPLAY 1.212766 (-12655 5703);
PAINT GREEN (-12655 5703);
DISPLAY INVISIBLE (-12655 5703);
FORCEPROP 2 LAST CDS_LIB passive
J 0
(-12550 5900);
DISPLAY INVISIBLE (-12550 5900);
FORCEADD VCC..1
R 1
(-13250 5850);
FORCEPROP 3 LASTPIN (-13200 5900) SIG_NAME XP3R3V_FPGA\g
J 0
(-13190 5910);
DISPLAY 0.659574 (-13190 5910);
PAINT MONO (-13190 5910);
DISPLAY INVISIBLE (-13190 5910);
FORCEPROP 0 LAST VOLTAGE 3.3V
J 0
(-13900 5900);
DISPLAY 1.021277 (-13900 5900);
DISPLAY BOTH (-13900 5900);
FORCEPROP 1 LAST HDL_POWER XP3R3V_FPGA
J 1
(-13600 5850);
DISPLAY 1.021277 (-13600 5850);
PAINT GREEN (-13600 5850);
FORCEPROP 1 LAST PATH I248
R 1
J 0
(-13340 5885);
DISPLAY 0.808511 (-13340 5885);
PAINT GREEN (-13340 5885);
DISPLAY INVISIBLE (-13340 5885);
FORCEPROP 1 LAST BODY_TYPE PLUMBING
R 1
J 0
(-13207 5805);
DISPLAY 0.340426 (-13207 5805);
PAINT GREEN (-13207 5805);
DISPLAY INVISIBLE (-13207 5805);
FORCEPROP 1 LAST CDS_LMAN_SYM_OUTLINE -250,250,250,-250
R 1
J 0
(-13250 5850);
DISPLAY 0.468085 (-13250 5850);
PAINT GREEN (-13250 5850);
DISPLAY INVISIBLE (-13250 5850);
FORCEPROP 2 LAST CDS_LIB cls
R 1
J 0
(-13250 5850);
DISPLAY INVISIBLE (-13250 5850);
FORCEADD VCC..1
(-2150 8150);
FORCEPROP 3 LASTPIN (-2100 8100) SIG_NAME XP3R3V_FPGA\g
J 0
(-2090 8110);
DISPLAY 0.659574 (-2090 8110);
PAINT MONO (-2090 8110);
DISPLAY INVISIBLE (-2090 8110);
FORCEPROP 1 LAST HDL_POWER XP3R3V_FPGA
J 1
(-2095 8205);
DISPLAY 1.021277 (-2095 8205);
PAINT GREEN (-2095 8205);
FORCEPROP 0 LAST VOLTAGE 3.3V
J 0
(-2400 8300);
DISPLAY 1.021277 (-2400 8300);
DISPLAY BOTH (-2400 8300);
FORCEPROP 2 LAST CDS_LIB cls
J 0
(-2150 8150);
DISPLAY INVISIBLE (-2150 8150);
FORCEPROP 1 LAST CDS_LMAN_SYM_OUTLINE -250,250,250,-250
J 0
(-2150 8150);
DISPLAY 0.468085 (-2150 8150);
PAINT GREEN (-2150 8150);
DISPLAY INVISIBLE (-2150 8150);
FORCEPROP 1 LAST BODY_TYPE PLUMBING
J 0
(-2195 8107);
DISPLAY 0.340426 (-2195 8107);
PAINT GREEN (-2195 8107);
DISPLAY INVISIBLE (-2195 8107);
FORCEPROP 1 LAST PATH I249
J 0
(-2115 8240);
DISPLAY 0.808511 (-2115 8240);
PAINT GREEN (-2115 8240);
DISPLAY INVISIBLE (-2115 8240);
FORCEADD GND_SG..1
(-2200 7550);
FORCEPROP 3 LASTPIN (-2150 7600) SIG_NAME SG\g
J 0
(-2140 7610);
DISPLAY 0.659574 (-2140 7610);
PAINT MONO (-2140 7610);
DISPLAY INVISIBLE (-2140 7610);
FORCEPROP 1 LAST HDL_POWER SG
J 1
(-2145 7455);
DISPLAY 0.808511 (-2145 7455);
PAINT GREEN (-2145 7455);
FORCEPROP 2 LAST CDS_LIB cls
J 0
(-2200 7550);
DISPLAY INVISIBLE (-2200 7550);
FORCEPROP 1 LAST CDS_LMAN_SYM_OUTLINE 0,0,100,-50
J 0
(-2200 7550);
DISPLAY 0.468085 (-2200 7550);
PAINT GREEN (-2200 7550);
DISPLAY INVISIBLE (-2200 7550);
FORCEPROP 1 LAST BODY_TYPE PLUMBING
J 0
(-2185 7535);
DISPLAY 0.808511 (-2185 7535);
PAINT GREEN (-2185 7535);
DISPLAY INVISIBLE (-2185 7535);
FORCEPROP 1 LAST PATH I250
J 0
(-2165 7550);
DISPLAY 0.808511 (-2165 7550);
PAINT GREEN (-2165 7550);
DISPLAY INVISIBLE (-2165 7550);
FORCEADD RESISTOR..2
R 1
(-2800 8000);
FORCEPROP 1 LAST $LOCATION R435
J 0
(-3200 8000);
DISPLAY 1.212766 (-3200 8000);
PAINT GREEN (-3200 8000);
FORCEPROP 0 LAST CDS_LOCATION R435
R 1
J 0
(-2600 8100);
DISPLAY 1.021277 (-2600 8100);
DISPLAY INVISIBLE (-2600 8100);
FORCEPROP 0 LAST $SEC 1
R 1
J 0
(-2600 8100);
DISPLAY 0.680851 (-2600 8100);
PAINT MONO (-2600 8100);
DISPLAY INVISIBLE (-2600 8100);
FORCEPROP 0 LAST CDS_SEC 1
R 1
J 0
(-2600 8100);
DISPLAY 1.021277 (-2600 8100);
DISPLAY INVISIBLE (-2600 8100);
FORCEPROP 0 LASTPIN (-2900 8000) $PN 1
J 2
(-2910 8010);
DISPLAY 0.680851 (-2910 8010);
PAINT MONO (-2910 8010);
FORCEPROP 0 LASTPIN (-2650 8000) $PN 2
J 0
(-2640 8010);
DISPLAY 0.680851 (-2640 8010);
PAINT MONO (-2640 8010);
FORCEPROP 0 LAST PACKAGE 0402
J 0
(-2850 8050);
DISPLAY 0.808511 (-2850 8050);
FORCEPROP 1 LAST VALUE 100KOHM
J 0
(-2600 8000);
DISPLAY 1.212766 (-2600 8000);
PAINT GREEN (-2600 8000);
FORCEPROP 1 LAST CLS_PN G155-11003-01
R 1
J 0
(-3000 7864);
DISPLAY 1.212766 (-3000 7864);
PAINT GREEN (-3000 7864);
DISPLAY INVISIBLE (-3000 7864);
FORCEPROP 1 LAST CDS_LMAN_SYM_OUTLINE -50,50,50,-100
R 1
J 0
(-2800 8000);
DISPLAY 0.468085 (-2800 8000);
PAINT GREEN (-2800 8000);
DISPLAY INVISIBLE (-2800 8000);
FORCEPROP 2 LAST CDS_LIB passive
J 0
(-2800 8000);
DISPLAY INVISIBLE (-2800 8000);
FORCEPROP 1 LAST TOLERANCE 1%
R 1
J 0
(-3055 7803);
DISPLAY 1.212766 (-3055 7803);
PAINT GREEN (-3055 7803);
DISPLAY INVISIBLE (-3055 7803);
FORCEPROP 1 LAST PATH I251
R 1
J 0
(-2905 7803);
DISPLAY 1.212766 (-2905 7803);
PAINT GREEN (-2905 7803);
DISPLAY INVISIBLE (-2905 7803);
FORCEADD RESISTOR..1
(-2800 7750);
FORCEPROP 1 LAST $LOCATION R223
J 0
(-3200 7750);
DISPLAY 1.212766 (-3200 7750);
PAINT GREEN (-3200 7750);
FORCEPROP 0 LAST CDS_LOCATION R223
J 0
(-2650 7650);
DISPLAY 1.021277 (-2650 7650);
DISPLAY INVISIBLE (-2650 7650);
FORCEPROP 0 LAST $SEC 1
J 0
(-2650 7650);
DISPLAY 0.680851 (-2650 7650);
PAINT MONO (-2650 7650);
DISPLAY INVISIBLE (-2650 7650);
FORCEPROP 0 LAST CDS_SEC 1
J 0
(-2650 7650);
DISPLAY 1.021277 (-2650 7650);
DISPLAY INVISIBLE (-2650 7650);
FORCEPROP 0 LASTPIN (-2900 7750) $PN 1
J 2
(-2910 7760);
DISPLAY 0.680851 (-2910 7760);
PAINT MONO (-2910 7760);
FORCEPROP 0 LASTPIN (-2650 7750) $PN 2
J 0
(-2640 7760);
DISPLAY 0.680851 (-2640 7760);
PAINT MONO (-2640 7760);
FORCEPROP 0 LAST PACKAGE 0402
J 2
(-2700 7800);
DISPLAY 0.808511 (-2700 7800);
FORCEPROP 1 LAST VALUE 1KOHM
J 2
(-2300 7750);
DISPLAY 1.212766 (-2300 7750);
PAINT GREEN (-2300 7750);
FORCEPROP 1 LAST TOLERANCE 1%
J 0
(-2997 8005);
DISPLAY 1.212766 (-2997 8005);
PAINT GREEN (-2997 8005);
DISPLAY INVISIBLE (-2997 8005);
FORCEPROP 2 LAST CDS_LIB passive
J 0
(-2800 7750);
DISPLAY INVISIBLE (-2800 7750);
FORCEPROP 1 LAST CDS_LMAN_SYM_OUTLINE -50,50,100,-50
J 0
(-2800 7750);
DISPLAY 0.468085 (-2800 7750);
PAINT GREEN (-2800 7750);
DISPLAY INVISIBLE (-2800 7750);
FORCEPROP 1 LAST CLS_PN G155-11001-01
J 0
(-2936 7950);
DISPLAY 1.212766 (-2936 7950);
PAINT GREEN (-2936 7950);
DISPLAY INVISIBLE (-2936 7950);
FORCEPROP 1 LAST PATH I252
J 0
(-2997 7855);
DISPLAY 1.212766 (-2997 7855);
PAINT GREEN (-2997 7855);
DISPLAY INVISIBLE (-2997 7855);
FORCEADD RESISTOR..1
R 4
(-2750 7650);
FORCEPROP 1 LAST $LOCATION R224
J 2
(-3000 7650);
DISPLAY 1.212766 (-3000 7650);
PAINT GREEN (-3000 7650);
FORCEPROP 0 LAST CDS_LOCATION R224
R 2
J 0
(-2900 7750);
DISPLAY 1.021277 (-2900 7750);
DISPLAY INVISIBLE (-2900 7750);
FORCEPROP 0 LAST $SEC 1
R 2
J 0
(-2900 7750);
DISPLAY 0.680851 (-2900 7750);
PAINT MONO (-2900 7750);
DISPLAY INVISIBLE (-2900 7750);
FORCEPROP 0 LAST CDS_SEC 1
R 2
J 0
(-2900 7750);
DISPLAY 1.021277 (-2900 7750);
DISPLAY INVISIBLE (-2900 7750);
FORCEPROP 0 LASTPIN (-2650 7650) $PN 1
J 0
(-2660 7660);
DISPLAY 0.680851 (-2660 7660);
PAINT MONO (-2660 7660);
FORCEPROP 0 LASTPIN (-2900 7650) $PN 2
J 2
(-2910 7660);
DISPLAY 0.680851 (-2910 7660);
PAINT MONO (-2910 7660);
FORCEPROP 0 LAST NO_ASSY TRUE
J 0
(-2950 7600);
DISPLAY 0.808511 (-2950 7600);
DISPLAY BOTH (-2950 7600);
FORCEPROP 0 LAST PACKAGE 0402
J 0
(-2850 7700);
DISPLAY 0.808511 (-2850 7700);
FORCEPROP 1 LAST VALUE 1KOHM
J 0
(-2600 7650);
DISPLAY 1.212766 (-2600 7650);
PAINT GREEN (-2600 7650);
FORCEPROP 2 LAST CDS_LIB passive
R 2
J 0
(-2750 7650);
DISPLAY INVISIBLE (-2750 7650);
FORCEPROP 1 LAST CDS_LMAN_SYM_OUTLINE -50,50,100,-50
R 2
J 0
(-2750 7650);
DISPLAY 0.468085 (-2750 7650);
PAINT GREEN (-2750 7650);
DISPLAY INVISIBLE (-2750 7650);
FORCEPROP 1 LAST TOLERANCE 1%
R 2
J 0
(-2553 7395);
DISPLAY 1.212766 (-2553 7395);
PAINT GREEN (-2553 7395);
DISPLAY INVISIBLE (-2553 7395);
FORCEPROP 1 LAST CLS_PN G155-11001-01
R 2
J 0
(-2614 7450);
DISPLAY 1.212766 (-2614 7450);
PAINT GREEN (-2614 7450);
DISPLAY INVISIBLE (-2614 7450);
FORCEPROP 1 LAST PATH I253
R 2
J 0
(-2553 7545);
DISPLAY 1.212766 (-2553 7545);
PAINT GREEN (-2553 7545);
DISPLAY INVISIBLE (-2553 7545);
FORCEADD OFFPAGE_BI..1
(-3650 8150);
FORCEPROP 2 LAST $XR0 24H7<> 
J 0
(-3590 8150);
DISPLAY 0.638298 (-3590 8150);
PAINT MONO (-3590 8150);
FORCEPROP 1 LAST BODY_TYPE COMMENT
J 0
(-3640 8285);
DISPLAY 0.808511 (-3640 8285);
PAINT GREEN (-3640 8285);
DISPLAY INVISIBLE (-3640 8285);
FORCEPROP 1 LAST CDS_LMAN_SYM_OUTLINE -50,50,50,-50
J 0
(-3650 8150);
DISPLAY 0.468085 (-3650 8150);
PAINT GREEN (-3650 8150);
DISPLAY INVISIBLE (-3650 8150);
FORCEPROP 2 LAST CDS_LIB cls
J 0
(-3650 8150);
DISPLAY INVISIBLE (-3650 8150);
FORCEPROP 1 LAST OFFPAGE TRUE
J 0
(-3640 8205);
DISPLAY 0.808511 (-3640 8205);
PAINT GREEN (-3640 8205);
DISPLAY INVISIBLE (-3640 8205);
FORCEPROP 2 LAST PATH I254
J 0
(-3550 8200);
DISPLAY 1.021277 (-3550 8200);
DISPLAY INVISIBLE (-3550 8200);
FORCEADD OFFPAGE_BI..1
(-3650 7950);
FORCEPROP 2 LAST $XR0 24K7<> 
J 0
(-3590 7950);
DISPLAY 0.638298 (-3590 7950);
PAINT MONO (-3590 7950);
FORCEPROP 1 LAST BODY_TYPE COMMENT
J 0
(-3640 8085);
DISPLAY 0.808511 (-3640 8085);
PAINT GREEN (-3640 8085);
DISPLAY INVISIBLE (-3640 8085);
FORCEPROP 1 LAST CDS_LMAN_SYM_OUTLINE -50,50,50,-50
J 0
(-3650 7950);
DISPLAY 0.468085 (-3650 7950);
PAINT GREEN (-3650 7950);
DISPLAY INVISIBLE (-3650 7950);
FORCEPROP 2 LAST CDS_LIB cls
J 0
(-3650 7950);
DISPLAY INVISIBLE (-3650 7950);
FORCEPROP 1 LAST OFFPAGE TRUE
J 0
(-3640 8005);
DISPLAY 0.808511 (-3640 8005);
PAINT GREEN (-3640 8005);
DISPLAY INVISIBLE (-3640 8005);
FORCEPROP 2 LAST PATH I255
J 0
(-3550 8000);
DISPLAY 1.021277 (-3550 8000);
DISPLAY INVISIBLE (-3550 8000);
FORCEADD OFFPAGE_BI..1
(-3650 8050);
FORCEPROP 2 LAST $XR0 24J7<> 
J 0
(-3590 8050);
DISPLAY 0.638298 (-3590 8050);
PAINT MONO (-3590 8050);
FORCEPROP 1 LAST CDS_LMAN_SYM_OUTLINE -50,50,50,-50
J 0
(-3650 8050);
DISPLAY 0.468085 (-3650 8050);
PAINT GREEN (-3650 8050);
DISPLAY INVISIBLE (-3650 8050);
FORCEPROP 2 LAST CDS_LIB cls
J 0
(-3650 8050);
DISPLAY INVISIBLE (-3650 8050);
FORCEPROP 1 LAST BODY_TYPE COMMENT
J 0
(-3640 8185);
DISPLAY 0.808511 (-3640 8185);
PAINT GREEN (-3640 8185);
DISPLAY INVISIBLE (-3640 8185);
FORCEPROP 1 LAST OFFPAGE TRUE
J 0
(-3640 8105);
DISPLAY 0.808511 (-3640 8105);
PAINT GREEN (-3640 8105);
DISPLAY INVISIBLE (-3640 8105);
FORCEPROP 2 LAST PATH I256
J 0
(-3550 8100);
DISPLAY 1.021277 (-3550 8100);
DISPLAY INVISIBLE (-3550 8100);
FORCEADD OFFPAGE_BI..1
(-3650 7850);
FORCEPROP 2 LAST $XR0 24L7<> 
J 0
(-3590 7850);
DISPLAY 0.638298 (-3590 7850);
PAINT MONO (-3590 7850);
FORCEPROP 1 LAST CDS_LMAN_SYM_OUTLINE -50,50,50,-50
J 0
(-3650 7850);
DISPLAY 0.468085 (-3650 7850);
PAINT GREEN (-3650 7850);
DISPLAY INVISIBLE (-3650 7850);
FORCEPROP 2 LAST CDS_LIB cls
J 0
(-3650 7850);
DISPLAY INVISIBLE (-3650 7850);
FORCEPROP 1 LAST BODY_TYPE COMMENT
J 0
(-3640 7985);
DISPLAY 0.808511 (-3640 7985);
PAINT GREEN (-3640 7985);
DISPLAY INVISIBLE (-3640 7985);
FORCEPROP 1 LAST OFFPAGE TRUE
J 0
(-3640 7905);
DISPLAY 0.808511 (-3640 7905);
PAINT GREEN (-3640 7905);
DISPLAY INVISIBLE (-3640 7905);
FORCEPROP 2 LAST PATH I257
J 0
(-3550 7900);
DISPLAY 1.021277 (-3550 7900);
DISPLAY INVISIBLE (-3550 7900);
FORCEADD RESISTOR..1
(-5350 8150);
FORCEPROP 1 LAST $LOCATION R234
J 2
(-5550 8150);
DISPLAY 1.212766 (-5550 8150);
PAINT GREEN (-5550 8150);
FORCEPROP 0 LAST CDS_LOCATION R234
J 0
(-5100 8250);
DISPLAY 1.021277 (-5100 8250);
DISPLAY INVISIBLE (-5100 8250);
FORCEPROP 0 LAST $SEC 1
J 0
(-5100 8250);
DISPLAY 0.680851 (-5100 8250);
PAINT MONO (-5100 8250);
DISPLAY INVISIBLE (-5100 8250);
FORCEPROP 0 LAST CDS_SEC 1
J 0
(-5100 8250);
DISPLAY 1.021277 (-5100 8250);
DISPLAY INVISIBLE (-5100 8250);
FORCEPROP 0 LASTPIN (-5450 8150) $PN 1
J 2
(-5460 8160);
DISPLAY 0.680851 (-5460 8160);
PAINT MONO (-5460 8160);
FORCEPROP 0 LASTPIN (-5200 8150) $PN 2
J 0
(-5190 8160);
DISPLAY 0.680851 (-5190 8160);
PAINT MONO (-5190 8160);
FORCEPROP 1 LAST VALUE 33OHM
J 0
(-5111 8155);
DISPLAY 1.212766 (-5111 8155);
PAINT GREEN (-5111 8155);
FORCEPROP 0 LAST PACKAGE 0402
J 0
(-5400 8200);
DISPLAY 0.638298 (-5400 8200);
FORCEPROP 1 LAST TOLERANCE 1%
J 0
(-5547 8405);
DISPLAY 1.212766 (-5547 8405);
PAINT GREEN (-5547 8405);
DISPLAY INVISIBLE (-5547 8405);
FORCEPROP 1 LAST CLS_PN G155-133R0-01
J 0
(-5486 8350);
DISPLAY 1.212766 (-5486 8350);
PAINT GREEN (-5486 8350);
DISPLAY INVISIBLE (-5486 8350);
FORCEPROP 1 LAST CDS_LMAN_SYM_OUTLINE -50,50,100,-50
J 0
(-5350 8150);
DISPLAY 0.468085 (-5350 8150);
PAINT GREEN (-5350 8150);
DISPLAY INVISIBLE (-5350 8150);
FORCEPROP 1 LAST PATH I258
J 0
(-5547 8255);
DISPLAY 1.212766 (-5547 8255);
PAINT GREEN (-5547 8255);
DISPLAY INVISIBLE (-5547 8255);
FORCEPROP 2 LAST CDS_LIB passive
J 0
(-5350 8150);
DISPLAY INVISIBLE (-5350 8150);
FORCEADD RESISTOR..1
(-5350 8050);
FORCEPROP 1 LAST $LOCATION R238
J 2
(-5550 8050);
DISPLAY 1.212766 (-5550 8050);
PAINT GREEN (-5550 8050);
FORCEPROP 0 LAST CDS_LOCATION R238
J 0
(-5100 8150);
DISPLAY 1.021277 (-5100 8150);
DISPLAY INVISIBLE (-5100 8150);
FORCEPROP 0 LAST $SEC 1
J 0
(-5100 8150);
DISPLAY 0.680851 (-5100 8150);
PAINT MONO (-5100 8150);
DISPLAY INVISIBLE (-5100 8150);
FORCEPROP 0 LAST CDS_SEC 1
J 0
(-5100 8150);
DISPLAY 1.021277 (-5100 8150);
DISPLAY INVISIBLE (-5100 8150);
FORCEPROP 0 LASTPIN (-5450 8050) $PN 1
J 2
(-5460 8060);
DISPLAY 0.680851 (-5460 8060);
PAINT MONO (-5460 8060);
FORCEPROP 0 LASTPIN (-5200 8050) $PN 2
J 0
(-5190 8060);
DISPLAY 0.680851 (-5190 8060);
PAINT MONO (-5190 8060);
FORCEPROP 0 LAST PACKAGE 0402
J 0
(-5400 8100);
DISPLAY 0.638298 (-5400 8100);
FORCEPROP 1 LAST VALUE 33OHM
J 0
(-5111 8055);
DISPLAY 1.212766 (-5111 8055);
PAINT GREEN (-5111 8055);
FORCEPROP 1 LAST PATH I259
J 0
(-5547 8155);
DISPLAY 1.212766 (-5547 8155);
PAINT GREEN (-5547 8155);
DISPLAY INVISIBLE (-5547 8155);
FORCEPROP 1 LAST TOLERANCE 1%
J 0
(-5547 8305);
DISPLAY 1.212766 (-5547 8305);
PAINT GREEN (-5547 8305);
DISPLAY INVISIBLE (-5547 8305);
FORCEPROP 1 LAST CLS_PN G155-133R0-01
J 0
(-5486 8250);
DISPLAY 1.212766 (-5486 8250);
PAINT GREEN (-5486 8250);
DISPLAY INVISIBLE (-5486 8250);
FORCEPROP 1 LAST CDS_LMAN_SYM_OUTLINE -50,50,100,-50
J 0
(-5350 8050);
DISPLAY 0.468085 (-5350 8050);
PAINT GREEN (-5350 8050);
DISPLAY INVISIBLE (-5350 8050);
FORCEPROP 2 LAST CDS_LIB passive
J 0
(-5350 8050);
DISPLAY INVISIBLE (-5350 8050);
FORCEADD RESISTOR..1
(-5350 7850);
FORCEPROP 1 LAST $LOCATION R348
J 2
(-5550 7850);
DISPLAY 1.212766 (-5550 7850);
PAINT GREEN (-5550 7850);
FORCEPROP 0 LAST CDS_LOCATION R348
J 0
(-5100 7950);
DISPLAY 1.021277 (-5100 7950);
DISPLAY INVISIBLE (-5100 7950);
FORCEPROP 0 LAST $SEC 1
J 0
(-5100 7950);
DISPLAY 0.680851 (-5100 7950);
PAINT MONO (-5100 7950);
DISPLAY INVISIBLE (-5100 7950);
FORCEPROP 0 LAST CDS_SEC 1
J 0
(-5100 7950);
DISPLAY 1.021277 (-5100 7950);
DISPLAY INVISIBLE (-5100 7950);
FORCEPROP 0 LASTPIN (-5450 7850) $PN 1
J 2
(-5460 7860);
DISPLAY 0.680851 (-5460 7860);
PAINT MONO (-5460 7860);
FORCEPROP 0 LASTPIN (-5200 7850) $PN 2
J 0
(-5190 7860);
DISPLAY 0.680851 (-5190 7860);
PAINT MONO (-5190 7860);
FORCEPROP 1 LAST VALUE 33OHM
J 0
(-5111 7855);
DISPLAY 1.212766 (-5111 7855);
PAINT GREEN (-5111 7855);
FORCEPROP 0 LAST PACKAGE 0402
J 0
(-5400 7900);
DISPLAY 0.638298 (-5400 7900);
FORCEPROP 1 LAST PATH I260
J 0
(-5547 7955);
DISPLAY 1.212766 (-5547 7955);
PAINT GREEN (-5547 7955);
DISPLAY INVISIBLE (-5547 7955);
FORCEPROP 1 LAST TOLERANCE 1%
J 0
(-5547 8105);
DISPLAY 1.212766 (-5547 8105);
PAINT GREEN (-5547 8105);
DISPLAY INVISIBLE (-5547 8105);
FORCEPROP 1 LAST CLS_PN G155-133R0-01
J 0
(-5486 8050);
DISPLAY 1.212766 (-5486 8050);
PAINT GREEN (-5486 8050);
DISPLAY INVISIBLE (-5486 8050);
FORCEPROP 1 LAST CDS_LMAN_SYM_OUTLINE -50,50,100,-50
J 0
(-5350 7850);
DISPLAY 0.468085 (-5350 7850);
PAINT GREEN (-5350 7850);
DISPLAY INVISIBLE (-5350 7850);
FORCEPROP 2 LAST CDS_LIB passive
J 0
(-5350 7850);
DISPLAY INVISIBLE (-5350 7850);
FORCEADD RESISTOR..1
(-5350 7950);
FORCEPROP 1 LAST $LOCATION R339
J 2
(-5550 7950);
DISPLAY 1.212766 (-5550 7950);
PAINT GREEN (-5550 7950);
FORCEPROP 0 LAST CDS_LOCATION R339
J 0
(-5100 8050);
DISPLAY 1.021277 (-5100 8050);
DISPLAY INVISIBLE (-5100 8050);
FORCEPROP 0 LAST $SEC 1
J 0
(-5100 8050);
DISPLAY 0.680851 (-5100 8050);
PAINT MONO (-5100 8050);
DISPLAY INVISIBLE (-5100 8050);
FORCEPROP 0 LAST CDS_SEC 1
J 0
(-5100 8050);
DISPLAY 1.021277 (-5100 8050);
DISPLAY INVISIBLE (-5100 8050);
FORCEPROP 0 LASTPIN (-5450 7950) $PN 1
J 2
(-5460 7960);
DISPLAY 0.680851 (-5460 7960);
PAINT MONO (-5460 7960);
FORCEPROP 0 LASTPIN (-5200 7950) $PN 2
J 0
(-5190 7960);
DISPLAY 0.680851 (-5190 7960);
PAINT MONO (-5190 7960);
FORCEPROP 0 LAST PACKAGE 0402
J 0
(-5400 8000);
DISPLAY 0.638298 (-5400 8000);
FORCEPROP 1 LAST VALUE 33OHM
J 0
(-5111 7955);
DISPLAY 1.212766 (-5111 7955);
PAINT GREEN (-5111 7955);
FORCEPROP 1 LAST PATH I261
J 0
(-5547 8055);
DISPLAY 1.212766 (-5547 8055);
PAINT GREEN (-5547 8055);
DISPLAY INVISIBLE (-5547 8055);
FORCEPROP 1 LAST TOLERANCE 1%
J 0
(-5547 8205);
DISPLAY 1.212766 (-5547 8205);
PAINT GREEN (-5547 8205);
DISPLAY INVISIBLE (-5547 8205);
FORCEPROP 1 LAST CLS_PN G155-133R0-01
J 0
(-5486 8150);
DISPLAY 1.212766 (-5486 8150);
PAINT GREEN (-5486 8150);
DISPLAY INVISIBLE (-5486 8150);
FORCEPROP 1 LAST CDS_LMAN_SYM_OUTLINE -50,50,100,-50
J 0
(-5350 7950);
DISPLAY 0.468085 (-5350 7950);
PAINT GREEN (-5350 7950);
DISPLAY INVISIBLE (-5350 7950);
FORCEPROP 2 LAST CDS_LIB passive
J 0
(-5350 7950);
DISPLAY INVISIBLE (-5350 7950);
FORCEADD OFFPAGE_OUT..1
(-3650 7150);
FORCEPROP 2 LAST $XR0 24J7< 
J 0
(-3595 7150);
DISPLAY 0.638298 (-3595 7150);
PAINT MONO (-3595 7150);
FORCEPROP 1 LAST OFFPAGE TRUE
J 0
(-3640 7205);
DISPLAY 0.808511 (-3640 7205);
PAINT GREEN (-3640 7205);
DISPLAY INVISIBLE (-3640 7205);
FORCEPROP 1 LAST CDS_LMAN_SYM_OUTLINE -50,50,50,-50
J 0
(-3650 7150);
DISPLAY 0.468085 (-3650 7150);
PAINT GREEN (-3650 7150);
DISPLAY INVISIBLE (-3650 7150);
FORCEPROP 2 LAST CDS_LIB cls
J 0
(-3650 7150);
DISPLAY INVISIBLE (-3650 7150);
FORCEPROP 1 LAST BODY_TYPE COMMENT
J 0
(-3640 7285);
DISPLAY 0.808511 (-3640 7285);
PAINT GREEN (-3640 7285);
DISPLAY INVISIBLE (-3640 7285);
FORCEPROP 2 LAST PATH I262
J 0
(-3550 7200);
DISPLAY 1.021277 (-3550 7200);
DISPLAY INVISIBLE (-3550 7200);
FORCEADD RESISTOR..1
(-5350 7150);
FORCEPROP 1 LAST $LOCATION R362
J 2
(-5550 7150);
DISPLAY 1.212766 (-5550 7150);
PAINT GREEN (-5550 7150);
FORCEPROP 0 LAST CDS_LOCATION R362
J 0
(-5100 7250);
DISPLAY 1.021277 (-5100 7250);
DISPLAY INVISIBLE (-5100 7250);
FORCEPROP 0 LAST $SEC 1
J 0
(-5100 7250);
DISPLAY 0.680851 (-5100 7250);
PAINT MONO (-5100 7250);
DISPLAY INVISIBLE (-5100 7250);
FORCEPROP 0 LAST CDS_SEC 1
J 0
(-5100 7250);
DISPLAY 1.021277 (-5100 7250);
DISPLAY INVISIBLE (-5100 7250);
FORCEPROP 0 LASTPIN (-5450 7150) $PN 1
J 2
(-5460 7160);
DISPLAY 0.680851 (-5460 7160);
PAINT MONO (-5460 7160);
FORCEPROP 0 LASTPIN (-5200 7150) $PN 2
J 0
(-5190 7160);
DISPLAY 0.680851 (-5190 7160);
PAINT MONO (-5190 7160);
FORCEPROP 0 LAST PACKAGE 0402
J 0
(-5400 7200);
DISPLAY 0.638298 (-5400 7200);
FORCEPROP 1 LAST VALUE 33OHM
J 0
(-5111 7155);
DISPLAY 1.212766 (-5111 7155);
PAINT GREEN (-5111 7155);
FORCEPROP 2 LAST CDS_LIB passive
J 0
(-5350 7150);
DISPLAY INVISIBLE (-5350 7150);
FORCEPROP 1 LAST CDS_LMAN_SYM_OUTLINE -50,50,100,-50
J 0
(-5350 7150);
DISPLAY 0.468085 (-5350 7150);
PAINT GREEN (-5350 7150);
DISPLAY INVISIBLE (-5350 7150);
FORCEPROP 1 LAST CLS_PN G155-133R0-01
J 0
(-5486 7350);
DISPLAY 1.212766 (-5486 7350);
PAINT GREEN (-5486 7350);
DISPLAY INVISIBLE (-5486 7350);
FORCEPROP 1 LAST TOLERANCE 1%
J 0
(-5547 7405);
DISPLAY 1.212766 (-5547 7405);
PAINT GREEN (-5547 7405);
DISPLAY INVISIBLE (-5547 7405);
FORCEPROP 1 LAST PATH I263
J 0
(-5547 7255);
DISPLAY 1.212766 (-5547 7255);
PAINT GREEN (-5547 7255);
DISPLAY INVISIBLE (-5547 7255);
FORCEADD OFFPAGE_IN..2
(-4650 4850);
FORCEPROP 2 LAST $XR0 21H7> 
J 0
(-4595 4850);
DISPLAY 0.638298 (-4595 4850);
PAINT MONO (-4595 4850);
FORCEPROP 2 LAST PATH I27
J 0
(-4600 4950);
DISPLAY 1.021277 (-4600 4950);
DISPLAY INVISIBLE (-4600 4950);
FORCEPROP 1 LAST OFFPAGE TRUE
J 0
(-4640 4905);
DISPLAY 0.808511 (-4640 4905);
PAINT GREEN (-4640 4905);
DISPLAY INVISIBLE (-4640 4905);
FORCEPROP 1 LAST BODY_TYPE COMMENT
J 0
(-4640 4985);
DISPLAY 0.808511 (-4640 4985);
PAINT GREEN (-4640 4985);
DISPLAY INVISIBLE (-4640 4985);
FORCEPROP 1 LAST CDS_LMAN_SYM_OUTLINE -50,50,50,-50
J 0
(-4650 4850);
DISPLAY 0.468085 (-4650 4850);
PAINT GREEN (-4650 4850);
DISPLAY INVISIBLE (-4650 4850);
FORCEPROP 2 LAST CDS_LIB cls
J 0
(-4650 4850);
DISPLAY INVISIBLE (-4650 4850);
FORCEADD OFFPAGE_OUT..1
(-4650 4950);
FORCEPROP 2 LAST $XR0 21H7< 
J 0
(-4595 4950);
DISPLAY 0.638298 (-4595 4950);
PAINT MONO (-4595 4950);
FORCEPROP 2 LAST PATH I28
J 0
(-4600 5050);
DISPLAY 1.021277 (-4600 5050);
DISPLAY INVISIBLE (-4600 5050);
FORCEPROP 1 LAST OFFPAGE TRUE
J 0
(-4640 5005);
DISPLAY 0.808511 (-4640 5005);
PAINT GREEN (-4640 5005);
DISPLAY INVISIBLE (-4640 5005);
FORCEPROP 1 LAST BODY_TYPE COMMENT
J 0
(-4640 5085);
DISPLAY 0.808511 (-4640 5085);
PAINT GREEN (-4640 5085);
DISPLAY INVISIBLE (-4640 5085);
FORCEPROP 2 LAST CDS_LIB cls
J 0
(-4650 4950);
DISPLAY INVISIBLE (-4650 4950);
FORCEPROP 1 LAST CDS_LMAN_SYM_OUTLINE -50,50,50,-50
J 0
(-4650 4950);
DISPLAY 0.468085 (-4650 4950);
PAINT GREEN (-4650 4950);
DISPLAY INVISIBLE (-4650 4950);
FORCEADD OFFPAGE_IN..2
R 2
(-11400 6250);
FORCEPROP 2 LAST $XR0 23E11> 
J 0
(-11614 6250);
DISPLAY 0.638298 (-11614 6250);
PAINT MONO (-11614 6250);
FORCEPROP 2 LAST $XR1 ?
J 0
(-11824 6250);
DISPLAY 0.638298 (-11824 6250);
PAINT MONO (-11824 6250);
FORCEPROP 1 LAST BODY_TYPE COMMENT
J 2
(-11410 6385);
DISPLAY 0.808511 (-11410 6385);
PAINT GREEN (-11410 6385);
DISPLAY INVISIBLE (-11410 6385);
FORCEPROP 1 LAST CDS_LMAN_SYM_OUTLINE -50,50,50,-50
J 2
(-11400 6250);
DISPLAY 0.468085 (-11400 6250);
PAINT GREEN (-11400 6250);
DISPLAY INVISIBLE (-11400 6250);
FORCEPROP 2 LAST CDS_LIB cls
J 0
(-11400 6250);
DISPLAY INVISIBLE (-11400 6250);
FORCEPROP 1 LAST OFFPAGE TRUE
J 2
(-11410 6305);
DISPLAY 0.808511 (-11410 6305);
PAINT GREEN (-11410 6305);
DISPLAY INVISIBLE (-11410 6305);
FORCEPROP 2 LAST PATH I34
J 0
(-11350 6350);
DISPLAY 1.021277 (-11350 6350);
DISPLAY INVISIBLE (-11350 6350);
FORCEADD OFFPAGE_OUT..1
R 2
(-11400 6550);
FORCEPROP 2 LAST $XR0 23G3< 
J 0
(-11583 6550);
DISPLAY 0.638298 (-11583 6550);
PAINT MONO (-11583 6550);
FORCEPROP 1 LAST OFFPAGE TRUE
J 2
(-11410 6605);
DISPLAY 0.808511 (-11410 6605);
PAINT GREEN (-11410 6605);
DISPLAY INVISIBLE (-11410 6605);
FORCEPROP 1 LAST BODY_TYPE COMMENT
J 2
(-11410 6685);
DISPLAY 0.808511 (-11410 6685);
PAINT GREEN (-11410 6685);
DISPLAY INVISIBLE (-11410 6685);
FORCEPROP 2 LAST PATH I35
J 0
(-11350 6650);
DISPLAY 1.021277 (-11350 6650);
DISPLAY INVISIBLE (-11350 6650);
FORCEPROP 2 LAST CDS_LIB cls
J 0
(-11400 6550);
DISPLAY INVISIBLE (-11400 6550);
FORCEPROP 1 LAST CDS_LMAN_SYM_OUTLINE -50,50,50,-50
J 2
(-11400 6550);
DISPLAY 0.468085 (-11400 6550);
PAINT GREEN (-11400 6550);
DISPLAY INVISIBLE (-11400 6550);
FORCEADD OFFPAGE_IN..2
(-4150 8350);
FORCEPROP 2 LAST $XR0 22F4> 
J 0
(-4095 8350);
DISPLAY 0.638298 (-4095 8350);
PAINT MONO (-4095 8350);
FORCEPROP 1 LAST BODY_TYPE COMMENT
J 0
(-4140 8485);
DISPLAY 0.808511 (-4140 8485);
PAINT GREEN (-4140 8485);
DISPLAY INVISIBLE (-4140 8485);
FORCEPROP 1 LAST CDS_LMAN_SYM_OUTLINE -50,50,50,-50
J 0
(-4150 8350);
DISPLAY 0.468085 (-4150 8350);
PAINT GREEN (-4150 8350);
DISPLAY INVISIBLE (-4150 8350);
FORCEPROP 2 LAST CDS_LIB cls
J 0
(-4150 8350);
DISPLAY INVISIBLE (-4150 8350);
FORCEPROP 1 LAST OFFPAGE TRUE
J 0
(-4140 8405);
DISPLAY 0.808511 (-4140 8405);
PAINT GREEN (-4140 8405);
DISPLAY INVISIBLE (-4140 8405);
FORCEPROP 2 LAST PATH I36
J 0
(-4100 8450);
DISPLAY 1.021277 (-4100 8450);
DISPLAY INVISIBLE (-4100 8450);
FORCEADD OFFPAGE_OUT..1
R 2
(-11400 6450);
FORCEPROP 2 LAST $XR0 23J3< 
J 0
(-11583 6450);
DISPLAY 0.638298 (-11583 6450);
PAINT MONO (-11583 6450);
FORCEPROP 1 LAST OFFPAGE TRUE
J 2
(-11410 6505);
DISPLAY 0.808511 (-11410 6505);
PAINT GREEN (-11410 6505);
DISPLAY INVISIBLE (-11410 6505);
FORCEPROP 1 LAST BODY_TYPE COMMENT
J 2
(-11410 6585);
DISPLAY 0.808511 (-11410 6585);
PAINT GREEN (-11410 6585);
DISPLAY INVISIBLE (-11410 6585);
FORCEPROP 2 LAST PATH I37
J 0
(-11350 6550);
DISPLAY 1.021277 (-11350 6550);
DISPLAY INVISIBLE (-11350 6550);
FORCEPROP 1 LAST CDS_LMAN_SYM_OUTLINE -50,50,50,-50
J 2
(-11400 6450);
DISPLAY 0.468085 (-11400 6450);
PAINT GREEN (-11400 6450);
DISPLAY INVISIBLE (-11400 6450);
FORCEPROP 2 LAST CDS_LIB cls
J 0
(-11400 6450);
DISPLAY INVISIBLE (-11400 6450);
FORCEADD OFFPAGE_IN..2
(-4650 3550);
FORCEPROP 2 LAST $XR0 24D13> 
J 0
(-4595 3550);
DISPLAY 0.638298 (-4595 3550);
PAINT MONO (-4595 3550);
FORCEPROP 2 LAST CDS_LIB cls
J 0
(-4650 3550);
DISPLAY INVISIBLE (-4650 3550);
FORCEPROP 1 LAST CDS_LMAN_SYM_OUTLINE -50,50,50,-50
J 0
(-4650 3550);
DISPLAY 0.468085 (-4650 3550);
PAINT GREEN (-4650 3550);
DISPLAY INVISIBLE (-4650 3550);
FORCEPROP 1 LAST BODY_TYPE COMMENT
J 0
(-4640 3685);
DISPLAY 0.808511 (-4640 3685);
PAINT GREEN (-4640 3685);
DISPLAY INVISIBLE (-4640 3685);
FORCEPROP 1 LAST OFFPAGE TRUE
J 0
(-4640 3605);
DISPLAY 0.808511 (-4640 3605);
PAINT GREEN (-4640 3605);
DISPLAY INVISIBLE (-4640 3605);
FORCEPROP 2 LAST PATH I38
J 0
(-4600 3650);
DISPLAY 1.021277 (-4600 3650);
DISPLAY INVISIBLE (-4600 3650);
FORCEADD OFFPAGE_OUT..1
(-4650 3950);
FORCEPROP 2 LAST $XR0 24D13< 
J 0
(-4595 3950);
DISPLAY 0.638298 (-4595 3950);
PAINT MONO (-4595 3950);
FORCEPROP 2 LAST PATH I39
J 0
(-4600 4050);
DISPLAY 1.021277 (-4600 4050);
DISPLAY INVISIBLE (-4600 4050);
FORCEPROP 1 LAST OFFPAGE TRUE
J 0
(-4640 4005);
DISPLAY 0.808511 (-4640 4005);
PAINT GREEN (-4640 4005);
DISPLAY INVISIBLE (-4640 4005);
FORCEPROP 2 LAST CDS_LIB cls
J 0
(-4650 3950);
DISPLAY INVISIBLE (-4650 3950);
FORCEPROP 1 LAST CDS_LMAN_SYM_OUTLINE -50,50,50,-50
J 0
(-4650 3950);
DISPLAY 0.468085 (-4650 3950);
PAINT GREEN (-4650 3950);
DISPLAY INVISIBLE (-4650 3950);
FORCEPROP 1 LAST BODY_TYPE COMMENT
J 0
(-4640 4085);
DISPLAY 0.808511 (-4640 4085);
PAINT GREEN (-4640 4085);
DISPLAY INVISIBLE (-4640 4085);
FORCEADD OFFPAGE_OUT..1
(-4150 8550);
FORCEPROP 2 LAST $XR0 22F4< 
J 0
(-4095 8550);
DISPLAY 0.638298 (-4095 8550);
PAINT MONO (-4095 8550);
FORCEPROP 2 LAST CDS_LIB cls
J 0
(-4150 8550);
DISPLAY INVISIBLE (-4150 8550);
FORCEPROP 1 LAST CDS_LMAN_SYM_OUTLINE -50,50,50,-50
J 0
(-4150 8550);
DISPLAY 0.468085 (-4150 8550);
PAINT GREEN (-4150 8550);
DISPLAY INVISIBLE (-4150 8550);
FORCEPROP 1 LAST BODY_TYPE COMMENT
J 0
(-4140 8685);
DISPLAY 0.808511 (-4140 8685);
PAINT GREEN (-4140 8685);
DISPLAY INVISIBLE (-4140 8685);
FORCEPROP 1 LAST OFFPAGE TRUE
J 0
(-4140 8605);
DISPLAY 0.808511 (-4140 8605);
PAINT GREEN (-4140 8605);
DISPLAY INVISIBLE (-4140 8605);
FORCEPROP 2 LAST PATH I42
J 0
(-4100 8650);
DISPLAY 1.021277 (-4100 8650);
DISPLAY INVISIBLE (-4100 8650);
FORCEADD OFFPAGE_IN..2
R 2
(-11400 7250);
FORCEPROP 2 LAST $XR0 22F4> 
J 0
(-11583 7250);
DISPLAY 0.638298 (-11583 7250);
PAINT MONO (-11583 7250);
FORCEPROP 1 LAST BODY_TYPE COMMENT
J 2
(-11410 7385);
DISPLAY 0.808511 (-11410 7385);
PAINT GREEN (-11410 7385);
DISPLAY INVISIBLE (-11410 7385);
FORCEPROP 2 LAST CDS_LIB cls
J 0
(-11400 7250);
DISPLAY INVISIBLE (-11400 7250);
FORCEPROP 1 LAST CDS_LMAN_SYM_OUTLINE -50,50,50,-50
J 2
(-11400 7250);
DISPLAY 0.468085 (-11400 7250);
PAINT GREEN (-11400 7250);
DISPLAY INVISIBLE (-11400 7250);
FORCEPROP 1 LAST OFFPAGE TRUE
J 2
(-11410 7305);
DISPLAY 0.808511 (-11410 7305);
PAINT GREEN (-11410 7305);
DISPLAY INVISIBLE (-11410 7305);
FORCEPROP 2 LAST PATH I43
J 0
(-11350 7350);
DISPLAY 1.021277 (-11350 7350);
DISPLAY INVISIBLE (-11350 7350);
FORCEADD OFFPAGE_IN..2
R 2
(-11400 7350);
FORCEPROP 2 LAST $XR0 22F12> 
J 0
(-11614 7350);
DISPLAY 0.638298 (-11614 7350);
PAINT MONO (-11614 7350);
FORCEPROP 2 LAST CDS_LIB cls
J 0
(-11400 7350);
DISPLAY INVISIBLE (-11400 7350);
FORCEPROP 1 LAST CDS_LMAN_SYM_OUTLINE -50,50,50,-50
J 2
(-11400 7350);
DISPLAY 0.468085 (-11400 7350);
PAINT GREEN (-11400 7350);
DISPLAY INVISIBLE (-11400 7350);
FORCEPROP 1 LAST BODY_TYPE COMMENT
J 2
(-11410 7485);
DISPLAY 0.808511 (-11410 7485);
PAINT GREEN (-11410 7485);
DISPLAY INVISIBLE (-11410 7485);
FORCEPROP 1 LAST OFFPAGE TRUE
J 2
(-11410 7405);
DISPLAY 0.808511 (-11410 7405);
PAINT GREEN (-11410 7405);
DISPLAY INVISIBLE (-11410 7405);
FORCEPROP 2 LAST PATH I44
J 0
(-11350 7450);
DISPLAY 1.021277 (-11350 7450);
DISPLAY INVISIBLE (-11350 7450);
FORCEADD OFFPAGE_OUT..1
(-4650 4450);
FORCEPROP 2 LAST $XR0 21K12<> 
J 0
(-4595 4450);
DISPLAY 0.638298 (-4595 4450);
PAINT MONO (-4595 4450);
FORCEPROP 2 LAST PATH I54
J 0
(-4600 4550);
DISPLAY 1.021277 (-4600 4550);
DISPLAY INVISIBLE (-4600 4550);
FORCEPROP 1 LAST OFFPAGE TRUE
J 0
(-4640 4505);
DISPLAY 0.808511 (-4640 4505);
PAINT GREEN (-4640 4505);
DISPLAY INVISIBLE (-4640 4505);
FORCEPROP 2 LAST CDS_LIB cls
J 0
(-4650 4450);
DISPLAY INVISIBLE (-4650 4450);
FORCEPROP 1 LAST CDS_LMAN_SYM_OUTLINE -50,50,50,-50
J 0
(-4650 4450);
DISPLAY 0.468085 (-4650 4450);
PAINT GREEN (-4650 4450);
DISPLAY INVISIBLE (-4650 4450);
FORCEPROP 1 LAST BODY_TYPE COMMENT
J 0
(-4640 4585);
DISPLAY 0.808511 (-4640 4585);
PAINT GREEN (-4640 4585);
DISPLAY INVISIBLE (-4640 4585);
FORCEADD OFFPAGE_IN..2
R 2
(-11400 5950);
FORCEPROP 2 LAST $XR0 21G7> 
J 0
(-11583 5950);
DISPLAY 0.638298 (-11583 5950);
PAINT MONO (-11583 5950);
FORCEPROP 1 LAST BODY_TYPE COMMENT
J 2
(-11410 6085);
DISPLAY 0.808511 (-11410 6085);
PAINT GREEN (-11410 6085);
DISPLAY INVISIBLE (-11410 6085);
FORCEPROP 1 LAST CDS_LMAN_SYM_OUTLINE -50,50,50,-50
J 2
(-11400 5950);
DISPLAY 0.468085 (-11400 5950);
PAINT GREEN (-11400 5950);
DISPLAY INVISIBLE (-11400 5950);
FORCEPROP 2 LAST CDS_LIB cls
J 0
(-11400 5950);
DISPLAY INVISIBLE (-11400 5950);
FORCEPROP 1 LAST OFFPAGE TRUE
J 2
(-11410 6005);
DISPLAY 0.808511 (-11410 6005);
PAINT GREEN (-11410 6005);
DISPLAY INVISIBLE (-11410 6005);
FORCEPROP 2 LAST PATH I55
J 0
(-11350 6050);
DISPLAY 1.021277 (-11350 6050);
DISPLAY INVISIBLE (-11350 6050);
FORCEADD OFFPAGE_IN..2
R 2
(-11400 6350);
FORCEPROP 2 LAST $XR0 23C11> 
J 0
(-11614 6350);
DISPLAY 0.638298 (-11614 6350);
PAINT MONO (-11614 6350);
FORCEPROP 2 LAST CDS_LIB cls
J 0
(-11400 6350);
DISPLAY INVISIBLE (-11400 6350);
FORCEPROP 1 LAST CDS_LMAN_SYM_OUTLINE -50,50,50,-50
J 2
(-11400 6350);
DISPLAY 0.468085 (-11400 6350);
PAINT GREEN (-11400 6350);
DISPLAY INVISIBLE (-11400 6350);
FORCEPROP 1 LAST BODY_TYPE COMMENT
J 2
(-11410 6485);
DISPLAY 0.808511 (-11410 6485);
PAINT GREEN (-11410 6485);
DISPLAY INVISIBLE (-11410 6485);
FORCEPROP 1 LAST OFFPAGE TRUE
J 2
(-11410 6405);
DISPLAY 0.808511 (-11410 6405);
PAINT GREEN (-11410 6405);
DISPLAY INVISIBLE (-11410 6405);
FORCEPROP 2 LAST PATH I60
J 0
(-11350 6450);
DISPLAY 1.021277 (-11350 6450);
DISPLAY INVISIBLE (-11350 6450);
FORCEADD OFFPAGE_OUT..1
R 2
(-11400 5650);
FORCEPROP 2 LAST $XR0 21G10< 
J 0
(-11614 5650);
DISPLAY 0.638298 (-11614 5650);
PAINT MONO (-11614 5650);
FORCEPROP 2 LAST CDS_LIB cls
J 0
(-11400 5650);
DISPLAY INVISIBLE (-11400 5650);
FORCEPROP 1 LAST CDS_LMAN_SYM_OUTLINE -50,50,50,-50
J 2
(-11400 5650);
DISPLAY 0.468085 (-11400 5650);
PAINT GREEN (-11400 5650);
DISPLAY INVISIBLE (-11400 5650);
FORCEPROP 1 LAST BODY_TYPE COMMENT
J 2
(-11410 5785);
DISPLAY 0.808511 (-11410 5785);
PAINT GREEN (-11410 5785);
DISPLAY INVISIBLE (-11410 5785);
FORCEPROP 1 LAST OFFPAGE TRUE
J 2
(-11410 5705);
DISPLAY 0.808511 (-11410 5705);
PAINT GREEN (-11410 5705);
DISPLAY INVISIBLE (-11410 5705);
FORCEPROP 2 LAST PATH I61
J 0
(-11350 5750);
DISPLAY 1.021277 (-11350 5750);
DISPLAY INVISIBLE (-11350 5750);
FORCEADD OFFPAGE_OUT..1
(-4650 4550);
FORCEPROP 2 LAST $XR0 21K12<> 
J 0
(-4595 4550);
DISPLAY 0.638298 (-4595 4550);
PAINT MONO (-4595 4550);
FORCEPROP 2 LAST PATH I62
J 0
(-4600 4650);
DISPLAY 1.021277 (-4600 4650);
DISPLAY INVISIBLE (-4600 4650);
FORCEPROP 1 LAST OFFPAGE TRUE
J 0
(-4640 4605);
DISPLAY 0.808511 (-4640 4605);
PAINT GREEN (-4640 4605);
DISPLAY INVISIBLE (-4640 4605);
FORCEPROP 2 LAST CDS_LIB cls
J 0
(-4650 4550);
DISPLAY INVISIBLE (-4650 4550);
FORCEPROP 1 LAST CDS_LMAN_SYM_OUTLINE -50,50,50,-50
J 0
(-4650 4550);
DISPLAY 0.468085 (-4650 4550);
PAINT GREEN (-4650 4550);
DISPLAY INVISIBLE (-4650 4550);
FORCEPROP 1 LAST BODY_TYPE COMMENT
J 0
(-4640 4685);
DISPLAY 0.808511 (-4640 4685);
PAINT GREEN (-4640 4685);
DISPLAY INVISIBLE (-4640 4685);
FORCEADD OFFPAGE_BI..1
R 4
(-11400 5150);
FORCEPROP 2 LAST $XR0 24H12<> 
J 0
(-11650 5150);
DISPLAY 0.638298 (-11650 5150);
PAINT MONO (-11650 5150);
FORCEPROP 1 LAST BODY_TYPE COMMENT
R 2
J 0
(-11410 5015);
DISPLAY 0.808511 (-11410 5015);
PAINT GREEN (-11410 5015);
DISPLAY INVISIBLE (-11410 5015);
FORCEPROP 1 LAST CDS_LMAN_SYM_OUTLINE -50,50,50,-50
R 2
J 0
(-11400 5150);
DISPLAY 0.468085 (-11400 5150);
PAINT GREEN (-11400 5150);
DISPLAY INVISIBLE (-11400 5150);
FORCEPROP 2 LAST CDS_LIB cls
J 0
(-11400 5150);
DISPLAY INVISIBLE (-11400 5150);
FORCEPROP 1 LAST OFFPAGE TRUE
R 2
J 0
(-11410 5095);
DISPLAY 0.808511 (-11410 5095);
PAINT GREEN (-11410 5095);
DISPLAY INVISIBLE (-11410 5095);
FORCEPROP 2 LAST PATH I70
J 0
(-11350 5250);
DISPLAY 1.021277 (-11350 5250);
DISPLAY INVISIBLE (-11350 5250);
FORCEADD OFFPAGE_OUT..1
R 2
(-11400 8350);
FORCEPROP 2 LAST $XR0 22F12< 
J 0
(-11614 8350);
DISPLAY 0.638298 (-11614 8350);
PAINT MONO (-11614 8350);
FORCEPROP 1 LAST BODY_TYPE COMMENT
J 2
(-11410 8485);
DISPLAY 0.808511 (-11410 8485);
PAINT GREEN (-11410 8485);
DISPLAY INVISIBLE (-11410 8485);
FORCEPROP 2 LAST CDS_LIB cls
J 2
(-11400 8350);
DISPLAY INVISIBLE (-11400 8350);
FORCEPROP 1 LAST CDS_LMAN_SYM_OUTLINE -50,50,50,-50
J 2
(-11400 8350);
DISPLAY 0.468085 (-11400 8350);
PAINT GREEN (-11400 8350);
DISPLAY INVISIBLE (-11400 8350);
FORCEPROP 1 LAST OFFPAGE TRUE
J 2
(-11410 8405);
DISPLAY 0.808511 (-11410 8405);
PAINT GREEN (-11410 8405);
DISPLAY INVISIBLE (-11410 8405);
FORCEPROP 2 LAST PATH I9
J 2
(-11450 8450);
DISPLAY 1.021277 (-11450 8450);
DISPLAY INVISIBLE (-11450 8450);
FORCEADD SHEET_A1..1
(-200 -250);
FORCEPROP 2 LAST CUSTOM_TXT_CDS <XR_PAGE_TITLE>
J 0
(-15770 11100);
DISPLAY 0.638298 (-15770 11100);
PAINT PINK (-15770 11100);
FORCEPROP 1 LAST CUSTOM_TXT_CDS <DOCNO>
J 0
(-2250 135);
DISPLAY 0.978723 (-2250 135);
FORCEPROP 1 LAST CUSTOM_TXT_CDS <CON_PAGE_NUM>
J 0
(-2355 -200);
DISPLAY 0.978723 (-2355 -200);
FORCEPROP 1 LAST CUSTOM_TXT_CDS <DATE>
J 0
(-900 -75);
DISPLAY 0.978723 (-900 -75);
FORCEPROP 1 LAST CUSTOM_TXT_CDS <TITLE>
J 1
(-1985 380);
DISPLAY 0.978723 (-1985 380);
FORCEPROP 1 LAST CUSTOM_TXT_CDS <DESIGNER>
J 0
(-900 350);
DISPLAY 0.978723 (-900 350);
FORCEPROP 1 LAST CUSTOM_TXT_CDS <CON_TOTAL_PAGES>
J 0
(-2045 -200);
DISPLAY 0.808511 (-2045 -200);
FORCEPROP 1 LAST CUSTOM_TXT_CDS <ASSY_PN>
J 0
(-2250 -75);
DISPLAY 0.978723 (-2250 -75);
FORCEPROP 1 LAST CUSTOM_TXT_CDS <DOCREV>
J 0
(-900 125);
DISPLAY 0.978723 (-900 125);
FORCEPROP 1 LAST TITLE FPGA_2/5
J 0
(-2700 650);
DISPLAY 3.042553 (-2700 650);
PAINT GREEN (-2700 650);
FORCEPROP 2 LAST CDS_XR_PAGE_TITLE CR-11 : @TIMECARD_LIB.TIMECARD(SCH_1):PAGE11
J 0
(-15770 11100);
DISPLAY 0.638298 (-15770 11100);
PAINT PINK (-15770 11100);
DISPLAY INVISIBLE (-15770 11100);
FORCEPROP 2 LAST CDS_LIB cls
J 0
(-200 -250);
DISPLAY INVISIBLE (-200 -250);
FORCEPROP 1 LAST CDS_LMAN_SYM_OUTLINE -15850,11500,200,-200
J 0
(-200 -250);
DISPLAY 0.468085 (-200 -250);
PAINT GREEN (-200 -250);
DISPLAY INVISIBLE (-200 -250);
FORCEPROP 2 LAST PAGE_BORDER TRUE
J 0
(-15770 11100);
DISPLAY 0.638298 (-15770 11100);
PAINT PINK (-15770 11100);
DISPLAY INVISIBLE (-15770 11100);
FORCEPROP 1 LAST COMMENT_BODY TRUE
J 0
(-190 -195);
DISPLAY 0.808511 (-190 -195);
DISPLAY INVISIBLE (-190 -195);
WIRE 16 -1 (-2150 7650)(-2150 7600);
WIRE 16 -1 (-2150 7650)(-2650 7650);
WIRE 16 -1 (-12650 5900)(-13200 5900);
WIRE 16 -1 (-2100 8000)(-2100 7750);
WIRE 16 -1 (-2650 8000)(-2100 8000);
WIRE 16 -1 (-2100 8100)(-2100 8000);
WIRE 16 -1 (-2100 7750)(-2650 7750);
WIRE 16 -1 (-3700 6700)(-3150 6700);
WIRE 16 -1 (-3150 6700)(-3150 6600);
WIRE 16 -1 (-3150 6600)(-3150 6500);
WIRE 16 -1 (-3700 6600)(-3150 6600);
WIRE 16 -1 (-2950 4500)(-2950 4400);
WIRE 16 -1 (-2950 4500)(-3550 4500);
WIRE 16 -1 (-2950 4300)(-2950 4400);
WIRE 16 -1 (-2950 4400)(-3550 4400);
WIRE 16 -1 (-12650 6200)(-13100 6200);
WIRE 16 -1 (-13100 6300)(-13100 6200);
WIRE 16 -1 (-13100 6200)(-13100 6150);
WIRE 16 -1 (-12650 6300)(-13100 6300);
WIRE 16 -1 (-13100 6900)(-13100 6300);
WIRE 16 -1 (-13100 7200)(-13100 6900);
WIRE 16 -1 (-12700 6900)(-13100 6900);
WIRE 16 -1 (-13100 7200)(-12700 7200);
WIRE 16 -1 (-13100 7300)(-13100 7200);
WIRE 16 -1 (-13100 7300)(-12700 7300);
WIRE 16 -1 (-11350 5950)(-11300 5950);
WIRE 16 -1 (-11300 5950)(-9600 5950);
FORCEPROP 2 LAST SIG_NAME FPGA_IN_MAC_10MHZ_OUT
J 0
(-11260 5960);
DISPLAY 1.021277 (-11260 5960);
WIRE 16 -1 (-11300 5900)(-11300 5950);
WIRE 16 -1 (-12400 5900)(-11300 5900);
WIRE 16 -1 (-3950 6700)(-4750 6700);
WIRE 16 -1 (-4750 6750)(-4750 6700);
WIRE 16 -1 (-4750 6750)(-4700 6750);
WIRE 16 -1 (-6600 6750)(-4750 6750);
FORCEPROP 2 LAST SIG_NAME ANT2_IN
J 0
(-5260 6760);
DISPLAY 1.021277 (-5260 6760);
WIRE 16 -1 (-5200 7150)(-3700 7150);
FORCEPROP 2 LAST SIG_NAME FPGA_FLASH_CS_N
J 0
(-4710 7160);
DISPLAY 1.021277 (-4710 7160);
WIRE 16 -1 (-3750 7650)(-2900 7650);
WIRE 16 -1 (-3750 7650)(-3750 7750);
WIRE 16 -1 (-2900 7750)(-3750 7750);
WIRE 16 -1 (-3750 7750)(-6600 7750);
FORCEPROP 2 LAST SIG_NAME PUDC
J 0
(-4710 7760);
DISPLAY 1.021277 (-4710 7760);
WIRE 16 -1 (-3950 6600)(-4750 6600);
WIRE 16 -1 (-4750 6600)(-4750 6650);
WIRE 16 -1 (-4750 6650)(-4700 6650);
WIRE 16 -1 (-6600 6650)(-4750 6650);
FORCEPROP 2 LAST SIG_NAME ANT1_IN
J 0
(-5260 6660);
DISPLAY 1.021277 (-5260 6660);
WIRE 16 -1 (-5450 7850)(-6600 7850);
FORCEPROP 2 LAST SIG_NAME FPGA_D03
J 0
(-6410 7860);
DISPLAY 1.021277 (-6410 7860);
WIRE 16 -1 (-6600 8350)(-4200 8350);
FORCEPROP 2 LAST SIG_NAME UART_GPS_TX_FPGA_RX
J 0
(-5660 8360);
DISPLAY 1.021277 (-5660 8360);
WIRE 16 -1 (-5200 8150)(-3700 8150);
FORCEPROP 2 LAST SIG_NAME FPGA_FLASH_DQ0_MOSI
J 0
(-4710 8160);
DISPLAY 1.021277 (-4710 8160);
WIRE 16 -1 (-5450 8050)(-6600 8050);
FORCEPROP 2 LAST SIG_NAME FPGA_D01
J 0
(-6410 8060);
DISPLAY 1.021277 (-6410 8060);
WIRE 16 -1 (-5450 7950)(-6600 7950);
FORCEPROP 2 LAST SIG_NAME FPGA_D02
J 0
(-6410 7960);
DISPLAY 1.021277 (-6410 7960);
WIRE 16 -1 (-5450 8150)(-6600 8150);
FORCEPROP 2 LAST SIG_NAME FPGA_D00_MOSI
J 0
(-6410 8160);
DISPLAY 1.021277 (-6410 8160);
WIRE 16 -1 (-11350 6350)(-11300 6350);
WIRE 16 -1 (-11300 6350)(-9600 6350);
FORCEPROP 2 LAST SIG_NAME ANT3_IN
J 0
(-11260 6360);
DISPLAY 1.021277 (-11260 6360);
WIRE 16 -1 (-11300 6300)(-11300 6350);
WIRE 16 -1 (-12400 6300)(-11300 6300);
WIRE 16 -1 (-6600 7150)(-5450 7150);
FORCEPROP 2 LAST SIG_NAME FPGA_FCS_B
J 0
(-6410 7160);
DISPLAY 1.021277 (-6410 7160);
WIRE 16 -1 (-11350 7750)(-9600 7750);
FORCEPROP 2 LAST SIG_NAME FPGA_IO_FT_USBDET_RST_N
J 0
(-11260 7760);
DISPLAY 1.021277 (-11260 7760);
WIRE 16 -1 (-9600 7950)(-11350 7950);
FORCEPROP 2 LAST SIG_NAME FPGA_OUT_SN_EEPROM_WP
J 0
(-11260 7960);
DISPLAY 1.021277 (-11260 7960);
WIRE 16 -1 (-6600 8550)(-4200 8550);
FORCEPROP 2 LAST SIG_NAME UART_GPS_RX_FPGA_TX
J 0
(-5660 8560);
DISPLAY 1.021277 (-5660 8560);
WIRE 16 -1 (-11350 6450)(-9600 6450);
FORCEPROP 2 LAST SIG_NAME ANT2_OUT
J 0
(-11260 6460);
DISPLAY 1.021277 (-11260 6460);
WIRE 16 -1 (-11300 7350)(-11300 7300);
WIRE 16 -1 (-11350 7350)(-11300 7350);
WIRE 16 -1 (-11300 7350)(-9600 7350);
FORCEPROP 2 LAST SIG_NAME FPGA_IN_GPSTP1_OUT
J 0
(-11260 7360);
DISPLAY 1.021277 (-11260 7360);
WIRE 16 -1 (-11300 7300)(-12450 7300);
WIRE 16 -1 (-11300 7250)(-11300 7200);
WIRE 16 -1 (-11350 7250)(-11300 7250);
WIRE 16 -1 (-11300 7250)(-9600 7250);
FORCEPROP 2 LAST SIG_NAME FPGA_IN_GPSTP2_OUT
J 0
(-11260 7260);
DISPLAY 1.021277 (-11260 7260);
WIRE 16 -1 (-11300 7200)(-12450 7200);
WIRE 16 -1 (-11350 6850)(-9600 6850);
FORCEPROP 2 LAST SIG_NAME FPGA_IN_MAC_ALARM_OUT_N
J 0
(-11260 6860);
DISPLAY 1.021277 (-11260 6860);
WIRE 16 -1 (-11350 6950)(-11300 6950);
WIRE 16 -1 (-11300 6950)(-9600 6950);
FORCEPROP 2 LAST SIG_NAME FPGA_IN_MAC_BITE OUT
J 0
(-11260 6960);
DISPLAY 1.021277 (-11260 6960);
WIRE 16 -1 (-11300 6900)(-11300 6950);
WIRE 16 -1 (-12450 6900)(-11300 6900);
WIRE 16 -1 (-11350 8050)(-9600 8050);
FORCEPROP 2 LAST SIG_NAME FPGA_EEPROM_I2C_SDA
J 0
(-11260 8060);
DISPLAY 1.021277 (-11260 8060);
WIRE 16 -1 (-11350 5150)(-9600 5150);
FORCEPROP 2 LAST SIG_NAME FPGA_PCA9546_I2C_SDA
J 0
(-11260 5160);
DISPLAY 1.021277 (-11260 5160);
WIRE 16 -1 (-11350 7850)(-9600 7850);
FORCEPROP 2 LAST SIG_NAME FPGA_OUT_SEC_EEPROM_WP
J 0
(-11260 7860);
DISPLAY 1.021277 (-11260 7860);
WIRE 16 -1 (-11350 8150)(-9600 8150);
FORCEPROP 2 LAST SIG_NAME FPGA_EEPROM_I2C_SCL
J 0
(-11260 8160);
DISPLAY 1.021277 (-11260 8160);
WIRE 16 -1 (-9600 5050)(-11350 5050);
FORCEPROP 2 LAST SIG_NAME FPGA_OUT_PCA9546_RST_N
J 0
(-11260 5060);
DISPLAY 1.021277 (-11260 5060);
WIRE 16 -1 (-11350 6050)(-9600 6050);
FORCEPROP 2 LAST SIG_NAME ANT4_OUT
J 0
(-11260 6060);
DISPLAY 1.021277 (-11260 6060);
WIRE 16 -1 (-11350 6150)(-9600 6150);
FORCEPROP 2 LAST SIG_NAME ANT3_OUT
J 0
(-11260 6160);
DISPLAY 1.021277 (-11260 6160);
WIRE 16 -1 (-12400 6200)(-11300 6200);
WIRE 16 -1 (-11300 6200)(-11300 6250);
WIRE 16 -1 (-11300 6250)(-9600 6250);
FORCEPROP 2 LAST SIG_NAME ANT4_IN
J 0
(-11260 6260);
DISPLAY 1.021277 (-11260 6260);
WIRE 16 -1 (-11350 6250)(-11300 6250);
WIRE 16 -1 (-11350 6550)(-9600 6550);
FORCEPROP 2 LAST SIG_NAME ANT1_OUT
J 0
(-11260 6560);
DISPLAY 1.021277 (-11260 6560);
WIRE 16 -1 (-11350 8350)(-9600 8350);
FORCEPROP 2 LAST SIG_NAME FPGA_OUT_GPS_RST_N
J 0
(-11260 8360);
DISPLAY 1.021277 (-11260 8360);
WIRE 16 -1 (-6600 3550)(-4700 3550);
FORCEPROP 2 LAST SIG_NAME UART_FT4232_TX_FPGA_RX
J 0
(-5860 3560);
DISPLAY 1.021277 (-5860 3560);
WIRE 16 -1 (-6600 3950)(-4700 3950);
FORCEPROP 2 LAST SIG_NAME UART_FT4232_RX_FPGA_TX
J 0
(-5810 3960);
DISPLAY 1.021277 (-5810 3960);
WIRE 16 -1 (-6600 4950)(-4700 4950);
FORCEPROP 2 LAST SIG_NAME UART_MAC_RX_FPGA_TX
J 0
(-5710 4960);
DISPLAY 1.021277 (-5710 4960);
WIRE 16 -1 (-6600 4150)(-4700 4150);
FORCEPROP 2 LAST SIG_NAME FPGA_PCA9546_I2C_SCL
J 0
(-5710 4160);
DISPLAY 1.021277 (-5710 4160);
WIRE 16 -1 (-6600 4850)(-4700 4850);
FORCEPROP 2 LAST SIG_NAME UART_MAC_TX_FPGA_RX
J 0
(-5710 4860);
DISPLAY 1.021277 (-5710 4860);
WIRE 16 -1 (-4750 4400)(-3800 4400);
WIRE 16 -1 (-4750 4450)(-4750 4400);
WIRE 16 -1 (-4750 4450)(-4700 4450);
WIRE 16 -1 (-6600 4450)(-4750 4450);
FORCEPROP 2 LAST SIG_NAME MAC_USB_DM
J 0
(-5260 4460);
DISPLAY 1.021277 (-5260 4460);
WIRE 16 -1 (-4750 4500)(-3800 4500);
WIRE 16 -1 (-4750 4550)(-4750 4500);
WIRE 16 -1 (-4750 4550)(-4700 4550);
WIRE 16 -1 (-6600 4550)(-4750 4550);
FORCEPROP 2 LAST SIG_NAME MAC_USB_DP
J 0
(-5260 4560);
DISPLAY 1.021277 (-5260 4560);
WIRE 16 -1 (-11350 5650)(-9600 5650);
FORCEPROP 2 LAST SIG_NAME FPGA_OUT_MACUSBPOWER_EN
J 0
(-11260 5660);
DISPLAY 1.021277 (-11260 5660);
WIRE 16 -1 (-6600 5850)(-4700 5850);
FORCEPROP 2 LAST SIG_NAME FPGA_M_RGB_LED_I2C_SCL
J 0
(-6060 5860);
DISPLAY 1.021277 (-6060 5860);
WIRE 16 -1 (-6600 5950)(-4700 5950);
FORCEPROP 2 LAST SIG_NAME FPGA_M_RGB_LED_I2C_SDA
J 0
(-6060 5960);
DISPLAY 1.021277 (-6060 5960);
WIRE 16 -1 (-4700 5750)(-6600 5750);
FORCEPROP 2 LAST SIG_NAME FPGA_OUT_RGB_LED_SHUTDOWN_N
J 0
(-6060 5760);
DISPLAY 1.021277 (-6060 5760);
WIRE 16 -1 (-3750 8000)(-2900 8000);
WIRE 16 -1 (-3750 8050)(-3750 8000);
WIRE 16 -1 (-3750 8050)(-3700 8050);
WIRE 16 -1 (-5200 8050)(-3750 8050);
FORCEPROP 2 LAST SIG_NAME FPGA_FLASH_DQ1_MISO
J 0
(-4710 8060);
DISPLAY 1.021277 (-4710 8060);
WIRE 16 -1 (-5200 7850)(-3700 7850);
FORCEPROP 2 LAST SIG_NAME FPGA_FLASH_DQ3
J 0
(-4710 7860);
DISPLAY 1.021277 (-4710 7860);
WIRE 16 -1 (-5200 7950)(-3700 7950);
FORCEPROP 2 LAST SIG_NAME FPGA_FLASH_DQ2
J 0
(-4710 7960);
DISPLAY 1.021277 (-4710 7960);
DOT 1 (-13100 6300);
DOT 1 (-13100 6900);
DOT 1 (-13100 7200);
DOT 1 (-11300 5950);
DOT 1 (-11300 6250);
DOT 1 (-11300 6950);
DOT 1 (-11300 7250);
DOT 1 (-11300 7350);
DOT 1 (-11300 6350);
DOT 1 (-13100 6200);
DOT 1 (-4750 4450);
DOT 1 (-4750 4550);
DOT 1 (-4750 6650);
DOT 1 (-4750 6750);
DOT 1 (-2950 4400);
DOT 1 (-3150 6600);
DOT 1 (-2100 8000);
DOT 1 (-3750 8050);
DOT 1 (-3750 7750);
FORCENOTE
PLACE R CLOSE TO FPGA'S PIN
(-13000 5800) 0;
DISPLAY LEFT (-13000 5800);
DISPLAY 1.021277 (-13000 5800);
FORCENOTE
PLACE R CLOSE TO FPGA'S PIN
(-5900 8250) 0;
DISPLAY LEFT (-5900 8250);
DISPLAY 1.021277 (-5900 8250);
FORCENOTE
PUDC HIGH:IO INTERNAL PULL UP DISABLE
(-4050 7500) 0;
DISPLAY LEFT (-4050 7500);
DISPLAY 1.021277 (-4050 7500);
FORCENOTE
PLACE R CLOSE TO FPGA'S PIN
(-4200 6850) 0;
DISPLAY LEFT (-4200 6850);
DISPLAY 1.021277 (-4200 6850);
FORCENOTE
FPGA 2/5
(-8750 10100) 0;
DISPLAY LEFT (-8750 10100);
DISPLAY 3.936170 (-8750 10100);
FORCENOTE
PLACE R CLOSE TO FPGA'S PIN
(-13050 7450) 0;
DISPLAY LEFT (-13050 7450);
DISPLAY 1.021277 (-13050 7450);
FORCENOTE
PLACE R CLOSE TO FPGA'S PIN
(-13050 6450) 0;
DISPLAY LEFT (-13050 6450);
DISPLAY 1.021277 (-13050 6450);
FORCENOTE
PLACE R CLOSE TO FPGA'S PIN
(-4100 4650) 0;
DISPLAY LEFT (-4100 4650);
DISPLAY 1.021277 (-4100 4650);
FORCENOTE
LOW:IO INTERNAL PULL UP ENABLE
(-3750 7400) 0;
DISPLAY LEFT (-3750 7400);
DISPLAY 1.021277 (-3750 7400);
QUIT
